(kicad_sch (version 20230121) (generator eeschema)

  (paper "A3")

  (title_block
    (title "Data Center RDIMM DDR4 Tester")
    (date "2024-09-30")
    (rev "1.2.4")
    (company "Antmicro Ltd.")
    (comment 1 "www.antmicro.com")
    (comment 2 "Antmicro Ltd")
  )


  (no_connect (at 68.58 147.955))
  (no_connect (at 144.78 112.395))
  (no_connect (at 68.58 188.595))
  (no_connect (at 68.58 165.735))
  (no_connect (at 144.78 201.295))
  (no_connect (at 245.11 196.215))
  (no_connect (at 245.11 203.835))
  (no_connect (at 245.11 206.375))
  (no_connect (at 245.11 211.455))
  (no_connect (at 144.78 92.075))
  (no_connect (at 144.78 94.615))
  (no_connect (at 144.78 158.115))
  (no_connect (at 144.78 132.715))
  (no_connect (at 68.58 94.615))
  (no_connect (at 68.58 104.775))
  (no_connect (at 144.78 97.155))
  (no_connect (at 245.11 155.575))
  (no_connect (at 144.78 163.195))
  (no_connect (at 144.78 109.855))
  (no_connect (at 144.78 213.995))
  (no_connect (at 144.78 122.555))
  (no_connect (at 144.78 125.095))
  (no_connect (at 68.58 178.435))
  (no_connect (at 245.11 208.915))
  (no_connect (at 68.58 186.055))
  (no_connect (at 144.78 99.695))
  (no_connect (at 144.78 203.835))
  (no_connect (at 68.58 97.155))
  (no_connect (at 245.11 186.055))
  (no_connect (at 68.58 107.315))
  (no_connect (at 144.78 183.515))
  (no_connect (at 144.78 140.335))
  (no_connect (at 245.11 150.495))
  (no_connect (at 144.78 165.735))
  (no_connect (at 144.78 211.455))
  (no_connect (at 144.78 147.955))
  (no_connect (at 245.11 193.675))
  (no_connect (at 68.58 130.175))
  (no_connect (at 68.58 122.555))
  (no_connect (at 144.78 173.355))
  (no_connect (at 144.78 193.675))
  (no_connect (at 144.78 114.935))
  (no_connect (at 144.78 120.015))
  (no_connect (at 68.58 120.015))
  (no_connect (at 144.78 104.775))
  (no_connect (at 68.58 160.655))
  (no_connect (at 245.11 191.135))
  (no_connect (at 144.78 188.595))
  (no_connect (at 144.78 117.475))
  (no_connect (at 144.78 180.975))
  (no_connect (at 144.78 127.635))
  (no_connect (at 144.78 168.275))
  (no_connect (at 68.58 127.635))
  (no_connect (at 144.78 150.495))
  (no_connect (at 144.78 102.235))
  (no_connect (at 144.78 145.415))
  (no_connect (at 68.58 183.515))
  (no_connect (at 245.11 188.595))
  (no_connect (at 245.11 158.115))
  (no_connect (at 245.11 201.295))
  (no_connect (at 245.11 216.535))
  (no_connect (at 68.58 92.075))
  (no_connect (at 68.58 180.975))
  (no_connect (at 68.58 175.895))
  (no_connect (at 144.78 191.135))
  (no_connect (at 144.78 130.175))
  (no_connect (at 144.78 107.315))
  (no_connect (at 144.78 153.035))
  (no_connect (at 144.78 142.875))
  (no_connect (at 245.11 92.075))
  (no_connect (at 144.78 170.815))
  (no_connect (at 245.11 213.995))

  (wire (pts (xy 321.945 198.755) (xy 327.66 198.755))
    (stroke (width 0) (type default))
  )
  (wire (pts (xy 241.3 198.755) (xy 245.11 198.755))
    (stroke (width 0) (type default))
  )
  (wire (pts (xy 64.77 206.375) (xy 68.58 206.375))
    (stroke (width 0) (type default))
  )
  (wire (pts (xy 321.945 186.055) (xy 327.66 186.055))
    (stroke (width 0) (type default))
  )
  (wire (pts (xy 64.77 216.535) (xy 68.58 216.535))
    (stroke (width 0) (type default))
  )
  (wire (pts (xy 321.945 135.255) (xy 327.66 135.255))
    (stroke (width 0) (type default))
  )
  (wire (pts (xy 241.3 127.635) (xy 245.11 127.635))
    (stroke (width 0) (type default))
  )
  (wire (pts (xy 241.3 183.515) (xy 245.11 183.515))
    (stroke (width 0) (type default))
  )
  (wire (pts (xy 241.3 132.715) (xy 245.11 132.715))
    (stroke (width 0) (type default))
  )
  (wire (pts (xy 321.945 107.315) (xy 327.66 107.315))
    (stroke (width 0) (type default))
  )
  (wire (pts (xy 321.945 208.915) (xy 327.66 208.915))
    (stroke (width 0) (type default))
  )
  (wire (pts (xy 139.7 216.535) (xy 144.78 216.535))
    (stroke (width 0) (type default))
  )
  (wire (pts (xy 321.945 183.515) (xy 327.66 183.515))
    (stroke (width 0) (type default))
  )
  (wire (pts (xy 64.77 193.675) (xy 68.58 193.675))
    (stroke (width 0) (type default))
  )
  (wire (pts (xy 321.945 140.335) (xy 327.66 140.335))
    (stroke (width 0) (type default))
  )
  (wire (pts (xy 64.77 191.135) (xy 68.58 191.135))
    (stroke (width 0) (type default))
  )
  (wire (pts (xy 241.3 153.035) (xy 245.11 153.035))
    (stroke (width 0) (type default))
  )
  (wire (pts (xy 241.3 102.235) (xy 245.11 102.235))
    (stroke (width 0) (type default))
  )
  (wire (pts (xy 241.3 104.775) (xy 245.11 104.775))
    (stroke (width 0) (type default))
  )
  (wire (pts (xy 139.7 178.435) (xy 144.78 178.435))
    (stroke (width 0) (type default))
  )
  (wire (pts (xy 64.77 155.575) (xy 68.58 155.575))
    (stroke (width 0) (type default))
  )
  (wire (pts (xy 321.945 127.635) (xy 327.66 127.635))
    (stroke (width 0) (type default))
  )
  (wire (pts (xy 241.3 168.275) (xy 245.11 168.275))
    (stroke (width 0) (type default))
  )
  (wire (pts (xy 64.77 135.255) (xy 68.58 135.255))
    (stroke (width 0) (type default))
  )
  (wire (pts (xy 321.945 104.775) (xy 327.66 104.775))
    (stroke (width 0) (type default))
  )
  (wire (pts (xy 241.3 112.395) (xy 245.11 112.395))
    (stroke (width 0) (type default))
  )
  (wire (pts (xy 241.3 135.255) (xy 245.11 135.255))
    (stroke (width 0) (type default))
  )
  (wire (pts (xy 64.77 137.795) (xy 68.58 137.795))
    (stroke (width 0) (type default))
  )
  (wire (pts (xy 241.3 165.735) (xy 245.11 165.735))
    (stroke (width 0) (type default))
  )
  (wire (pts (xy 321.945 147.955) (xy 327.66 147.955))
    (stroke (width 0) (type default))
  )
  (wire (pts (xy 321.945 92.075) (xy 327.66 92.075))
    (stroke (width 0) (type default))
  )
  (wire (pts (xy 241.3 122.555) (xy 245.11 122.555))
    (stroke (width 0) (type default))
  )
  (wire (pts (xy 245.11 86.995) (xy 241.3 86.995))
    (stroke (width 0) (type default))
  )
  (wire (pts (xy 139.7 198.755) (xy 144.78 198.755))
    (stroke (width 0) (type default))
  )
  (wire (pts (xy 321.945 125.095) (xy 327.66 125.095))
    (stroke (width 0) (type default))
  )
  (wire (pts (xy 321.945 165.735) (xy 327.66 165.735))
    (stroke (width 0) (type default))
  )
  (wire (pts (xy 321.945 114.935) (xy 327.66 114.935))
    (stroke (width 0) (type default))
  )
  (wire (pts (xy 321.945 117.475) (xy 327.66 117.475))
    (stroke (width 0) (type default))
  )
  (wire (pts (xy 321.945 213.995) (xy 327.66 213.995))
    (stroke (width 0) (type default))
  )
  (wire (pts (xy 241.3 114.935) (xy 245.11 114.935))
    (stroke (width 0) (type default))
  )
  (wire (pts (xy 321.945 163.195) (xy 327.66 163.195))
    (stroke (width 0) (type default))
  )
  (wire (pts (xy 321.945 170.815) (xy 327.66 170.815))
    (stroke (width 0) (type default))
  )
  (wire (pts (xy 321.945 158.115) (xy 327.66 158.115))
    (stroke (width 0) (type default))
  )
  (wire (pts (xy 321.945 201.295) (xy 327.66 201.295))
    (stroke (width 0) (type default))
  )
  (wire (pts (xy 139.7 175.895) (xy 144.78 175.895))
    (stroke (width 0) (type default))
  )
  (wire (pts (xy 321.945 142.875) (xy 327.66 142.875))
    (stroke (width 0) (type default))
  )
  (wire (pts (xy 64.77 170.815) (xy 68.58 170.815))
    (stroke (width 0) (type default))
  )
  (wire (pts (xy 321.945 122.555) (xy 327.66 122.555))
    (stroke (width 0) (type default))
  )
  (wire (pts (xy 64.77 150.495) (xy 68.58 150.495))
    (stroke (width 0) (type default))
  )
  (wire (pts (xy 241.3 109.855) (xy 245.11 109.855))
    (stroke (width 0) (type default))
  )
  (wire (pts (xy 64.77 158.115) (xy 68.58 158.115))
    (stroke (width 0) (type default))
  )
  (wire (pts (xy 321.945 173.355) (xy 327.66 173.355))
    (stroke (width 0) (type default))
  )
  (wire (pts (xy 321.945 206.375) (xy 327.66 206.375))
    (stroke (width 0) (type default))
  )
  (wire (pts (xy 241.3 160.655) (xy 245.11 160.655))
    (stroke (width 0) (type default))
  )
  (wire (pts (xy 241.3 170.815) (xy 245.11 170.815))
    (stroke (width 0) (type default))
  )
  (wire (pts (xy 321.945 130.175) (xy 327.66 130.175))
    (stroke (width 0) (type default))
  )
  (wire (pts (xy 64.77 112.395) (xy 68.58 112.395))
    (stroke (width 0) (type default))
  )
  (wire (pts (xy 64.77 145.415) (xy 68.58 145.415))
    (stroke (width 0) (type default))
  )
  (wire (pts (xy 321.945 120.015) (xy 327.66 120.015))
    (stroke (width 0) (type default))
  )
  (wire (pts (xy 241.3 137.795) (xy 245.11 137.795))
    (stroke (width 0) (type default))
  )
  (wire (pts (xy 64.77 114.935) (xy 68.58 114.935))
    (stroke (width 0) (type default))
  )
  (wire (pts (xy 321.945 97.155) (xy 327.66 97.155))
    (stroke (width 0) (type default))
  )
  (wire (pts (xy 139.7 155.575) (xy 144.78 155.575))
    (stroke (width 0) (type default))
  )
  (wire (pts (xy 64.77 125.095) (xy 68.58 125.095))
    (stroke (width 0) (type default))
  )
  (wire (pts (xy 64.77 102.235) (xy 68.58 102.235))
    (stroke (width 0) (type default))
  )
  (wire (pts (xy 321.945 191.135) (xy 327.66 191.135))
    (stroke (width 0) (type default))
  )
  (wire (pts (xy 64.77 99.695) (xy 68.58 99.695))
    (stroke (width 0) (type default))
  )
  (wire (pts (xy 241.3 117.475) (xy 245.11 117.475))
    (stroke (width 0) (type default))
  )
  (wire (pts (xy 241.3 178.435) (xy 245.11 178.435))
    (stroke (width 0) (type default))
  )
  (wire (pts (xy 241.3 140.335) (xy 245.11 140.335))
    (stroke (width 0) (type default))
  )
  (wire (pts (xy 139.7 206.375) (xy 144.78 206.375))
    (stroke (width 0) (type default))
  )
  (wire (pts (xy 64.77 163.195) (xy 68.58 163.195))
    (stroke (width 0) (type default))
  )
  (wire (pts (xy 321.945 150.495) (xy 327.66 150.495))
    (stroke (width 0) (type default))
  )
  (wire (pts (xy 64.77 142.875) (xy 68.58 142.875))
    (stroke (width 0) (type default))
  )
  (wire (pts (xy 139.7 208.915) (xy 144.78 208.915))
    (stroke (width 0) (type default))
  )
  (wire (pts (xy 139.7 160.655) (xy 144.78 160.655))
    (stroke (width 0) (type default))
  )
  (wire (pts (xy 139.7 186.055) (xy 144.78 186.055))
    (stroke (width 0) (type default))
  )
  (polyline (pts (xy 210.185 12.065) (xy 210.185 285.115))
    (stroke (width 0) (type default))
  )

  (wire (pts (xy 64.77 208.915) (xy 68.58 208.915))
    (stroke (width 0) (type default))
  )
  (wire (pts (xy 241.3 175.895) (xy 245.11 175.895))
    (stroke (width 0) (type default))
  )
  (wire (pts (xy 241.3 107.315) (xy 245.11 107.315))
    (stroke (width 0) (type default))
  )
  (wire (pts (xy 64.77 198.755) (xy 68.58 198.755))
    (stroke (width 0) (type default))
  )
  (wire (pts (xy 321.945 155.575) (xy 327.66 155.575))
    (stroke (width 0) (type default))
  )
  (wire (pts (xy 321.945 196.215) (xy 327.66 196.215))
    (stroke (width 0) (type default))
  )
  (wire (pts (xy 321.945 86.995) (xy 327.66 86.995))
    (stroke (width 0) (type default))
  )
  (wire (pts (xy 321.945 178.435) (xy 327.66 178.435))
    (stroke (width 0) (type default))
  )
  (wire (pts (xy 241.3 173.355) (xy 245.11 173.355))
    (stroke (width 0) (type default))
  )
  (wire (pts (xy 64.77 211.455) (xy 68.58 211.455))
    (stroke (width 0) (type default))
  )
  (wire (pts (xy 64.77 173.355) (xy 68.58 173.355))
    (stroke (width 0) (type default))
  )
  (wire (pts (xy 321.945 188.595) (xy 327.66 188.595))
    (stroke (width 0) (type default))
  )
  (wire (pts (xy 64.77 168.275) (xy 68.58 168.275))
    (stroke (width 0) (type default))
  )
  (wire (pts (xy 321.945 102.235) (xy 327.66 102.235))
    (stroke (width 0) (type default))
  )
  (wire (pts (xy 139.7 135.255) (xy 144.78 135.255))
    (stroke (width 0) (type default))
  )
  (wire (pts (xy 241.3 97.155) (xy 245.11 97.155))
    (stroke (width 0) (type default))
  )
  (wire (pts (xy 241.3 94.615) (xy 245.11 94.615))
    (stroke (width 0) (type default))
  )
  (wire (pts (xy 321.945 216.535) (xy 327.66 216.535))
    (stroke (width 0) (type default))
  )
  (wire (pts (xy 241.3 125.095) (xy 245.11 125.095))
    (stroke (width 0) (type default))
  )
  (wire (pts (xy 64.77 140.335) (xy 68.58 140.335))
    (stroke (width 0) (type default))
  )
  (wire (pts (xy 321.945 211.455) (xy 327.66 211.455))
    (stroke (width 0) (type default))
  )
  (wire (pts (xy 321.945 112.395) (xy 327.66 112.395))
    (stroke (width 0) (type default))
  )
  (wire (pts (xy 321.945 94.615) (xy 327.66 94.615))
    (stroke (width 0) (type default))
  )
  (wire (pts (xy 68.58 86.995) (xy 64.77 86.995))
    (stroke (width 0) (type default))
  )
  (wire (pts (xy 321.945 160.655) (xy 327.66 160.655))
    (stroke (width 0) (type default))
  )
  (wire (pts (xy 241.3 180.975) (xy 245.11 180.975))
    (stroke (width 0) (type default))
  )
  (wire (pts (xy 241.3 130.175) (xy 245.11 130.175))
    (stroke (width 0) (type default))
  )
  (wire (pts (xy 321.945 109.855) (xy 327.66 109.855))
    (stroke (width 0) (type default))
  )
  (wire (pts (xy 241.3 145.415) (xy 245.11 145.415))
    (stroke (width 0) (type default))
  )
  (wire (pts (xy 241.3 142.875) (xy 245.11 142.875))
    (stroke (width 0) (type default))
  )
  (wire (pts (xy 241.3 120.015) (xy 245.11 120.015))
    (stroke (width 0) (type default))
  )
  (wire (pts (xy 321.945 153.035) (xy 327.66 153.035))
    (stroke (width 0) (type default))
  )
  (wire (pts (xy 64.77 203.835) (xy 68.58 203.835))
    (stroke (width 0) (type default))
  )
  (wire (pts (xy 321.945 203.835) (xy 327.66 203.835))
    (stroke (width 0) (type default))
  )
  (wire (pts (xy 321.945 180.975) (xy 327.66 180.975))
    (stroke (width 0) (type default))
  )
  (wire (pts (xy 241.3 163.195) (xy 245.11 163.195))
    (stroke (width 0) (type default))
  )
  (wire (pts (xy 64.77 117.475) (xy 68.58 117.475))
    (stroke (width 0) (type default))
  )
  (wire (pts (xy 321.945 137.795) (xy 327.66 137.795))
    (stroke (width 0) (type default))
  )
  (wire (pts (xy 321.945 132.715) (xy 327.66 132.715))
    (stroke (width 0) (type default))
  )
  (wire (pts (xy 64.77 153.035) (xy 68.58 153.035))
    (stroke (width 0) (type default))
  )
  (wire (pts (xy 241.3 99.695) (xy 245.11 99.695))
    (stroke (width 0) (type default))
  )
  (wire (pts (xy 321.945 168.275) (xy 327.66 168.275))
    (stroke (width 0) (type default))
  )
  (wire (pts (xy 139.7 86.995) (xy 144.78 86.995))
    (stroke (width 0) (type default))
  )
  (wire (pts (xy 64.77 201.295) (xy 68.58 201.295))
    (stroke (width 0) (type default))
  )
  (wire (pts (xy 321.945 145.415) (xy 327.66 145.415))
    (stroke (width 0) (type default))
  )
  (wire (pts (xy 321.945 193.675) (xy 327.66 193.675))
    (stroke (width 0) (type default))
  )
  (wire (pts (xy 139.7 137.795) (xy 144.78 137.795))
    (stroke (width 0) (type default))
  )
  (wire (pts (xy 139.7 196.215) (xy 144.78 196.215))
    (stroke (width 0) (type default))
  )
  (wire (pts (xy 64.77 132.715) (xy 68.58 132.715))
    (stroke (width 0) (type default))
  )
  (wire (pts (xy 64.77 196.215) (xy 68.58 196.215))
    (stroke (width 0) (type default))
  )
  (wire (pts (xy 64.77 213.995) (xy 68.58 213.995))
    (stroke (width 0) (type default))
  )
  (wire (pts (xy 321.945 175.895) (xy 327.66 175.895))
    (stroke (width 0) (type default))
  )
  (wire (pts (xy 241.3 147.955) (xy 245.11 147.955))
    (stroke (width 0) (type default))
  )
  (wire (pts (xy 321.945 99.695) (xy 327.66 99.695))
    (stroke (width 0) (type default))
  )
  (wire (pts (xy 64.77 109.855) (xy 68.58 109.855))
    (stroke (width 0) (type default))
  )

  (text "BANK 12" (at 76.2 63.5 0)
    (effects (font (size 2.9972 2.9972) (thickness 0.5994) bold) (justify left bottom))
  )
  (text "BANK 15" (at 335.915 64.135 0)
    (effects (font (size 2.9972 2.9972) (thickness 0.5994) bold) (justify left bottom))
  )
  (text "BANK 14" (at 253.365 64.135 0)
    (effects (font (size 2.9972 2.9972) (thickness 0.5994) bold) (justify left bottom))
  )
  (text "BANK 13" (at 151.765 64.135 0)
    (effects (font (size 2.9972 2.9972) (thickness 0.5994) bold) (justify left bottom))
  )
  (text "VCCO (HR banks) max: 3.6V" (at 291.465 81.28 0)
    (effects (font (size 1.27 1.27)) (justify left bottom))
  )
  (text "VCCO (HR banks) max: 3.6V" (at 102.87 81.28 0)
    (effects (font (size 1.27 1.27)) (justify left bottom))
  )

  (global_label "FMC_IO_11_N" (shape input) (at 321.945 147.955 180) (fields_autoplaced)
    (effects (font (size 1.27 1.27)) (justify right))
    (property "Intersheetrefs" "${INTERSHEET_REFS}" (at 308.4327 147.8756 0)
      (effects (font (size 1.27 1.27)) (justify right) hide)
    )
  )
  (global_label "FMC_IO_15_N" (shape input) (at 321.945 168.275 180) (fields_autoplaced)
    (effects (font (size 1.27 1.27)) (justify right))
    (property "Intersheetrefs" "${INTERSHEET_REFS}" (at 308.4327 168.1956 0)
      (effects (font (size 1.27 1.27)) (justify right) hide)
    )
  )
  (global_label "USR_LED3" (shape input) (at 241.3 142.875 180) (fields_autoplaced)
    (effects (font (size 1.27 1.27)) (justify right))
    (property "Intersheetrefs" "${INTERSHEET_REFS}" (at -12.065 -0.635 0)
      (effects (font (size 1.27 1.27)) hide)
    )
  )
  (global_label "VDDQ" (shape input) (at 139.7 86.995 180) (fields_autoplaced)
    (effects (font (size 1.27 1.27)) (justify right))
    (property "Intersheetrefs" "${INTERSHEET_REFS}" (at 78.74 241.935 0)
      (effects (font (size 1.27 1.27)) hide)
    )
  )
  (global_label "PUDC_B" (shape input) (at 241.3 104.775 180) (fields_autoplaced)
    (effects (font (size 1.27 1.27)) (justify right))
    (property "Intersheetrefs" "${INTERSHEET_REFS}" (at -12.065 -0.635 0)
      (effects (font (size 1.27 1.27)) hide)
    )
  )
  (global_label "FMC_IO_2_N" (shape input) (at 321.945 102.235 180) (fields_autoplaced)
    (effects (font (size 1.27 1.27)) (justify right))
    (property "Intersheetrefs" "${INTERSHEET_REFS}" (at 308.4327 102.1556 0)
      (effects (font (size 1.27 1.27)) (justify right) hide)
    )
  )
  (global_label "ETH_INT_N" (shape input) (at 64.77 216.535 180) (fields_autoplaced)
    (effects (font (size 1.27 1.27)) (justify right))
    (property "Intersheetrefs" "${INTERSHEET_REFS}" (at 5.08 0 0)
      (effects (font (size 1.27 1.27)) hide)
    )
  )
  (global_label "FPGA_SLP_S4" (shape input) (at 241.3 180.975 180) (fields_autoplaced)
    (effects (font (size 1.27 1.27)) (justify right))
    (property "Intersheetrefs" "${INTERSHEET_REFS}" (at 226.3968 180.8956 0)
      (effects (font (size 1.27 1.27)) (justify right) hide)
    )
  )
  (global_label "CB6" (shape input) (at 139.7 155.575 180) (fields_autoplaced)
    (effects (font (size 1.27 1.27)) (justify right))
    (property "Intersheetrefs" "${INTERSHEET_REFS}" (at 511.81 -38.1 0)
      (effects (font (size 1.27 1.27)) (justify left) hide)
    )
  )
  (global_label "HOT_SWAP_GREEN" (shape input) (at 241.3 145.415 180) (fields_autoplaced)
    (effects (font (size 1.27 1.27)) (justify right))
    (property "Intersheetrefs" "${INTERSHEET_REFS}" (at 222.2239 145.3356 0)
      (effects (font (size 1.27 1.27)) (justify right) hide)
    )
  )
  (global_label "HR_CKP" (shape input) (at 64.77 196.215 180) (fields_autoplaced)
    (effects (font (size 1.27 1.27)) (justify right))
    (property "Intersheetrefs" "${INTERSHEET_REFS}" (at 5.08 0 0)
      (effects (font (size 1.27 1.27)) hide)
    )
  )
  (global_label "FMC_IO_17_P" (shape input) (at 321.945 175.895 180) (fields_autoplaced)
    (effects (font (size 1.27 1.27)) (justify right))
    (property "Intersheetrefs" "${INTERSHEET_REFS}" (at 308.4932 175.8156 0)
      (effects (font (size 1.27 1.27)) (justify right) hide)
    )
  )
  (global_label "ETH_RXD1" (shape input) (at 64.77 114.935 180) (fields_autoplaced)
    (effects (font (size 1.27 1.27)) (justify right))
    (property "Intersheetrefs" "${INTERSHEET_REFS}" (at 5.08 0 0)
      (effects (font (size 1.27 1.27)) hide)
    )
  )
  (global_label "ETH_RX_DV" (shape input) (at 64.77 140.335 180) (fields_autoplaced)
    (effects (font (size 1.27 1.27)) (justify right))
    (property "Intersheetrefs" "${INTERSHEET_REFS}" (at 5.08 0 0)
      (effects (font (size 1.27 1.27)) hide)
    )
  )
  (global_label "FMC_IO_12_N" (shape input) (at 321.945 153.035 180) (fields_autoplaced)
    (effects (font (size 1.27 1.27)) (justify right))
    (property "Intersheetrefs" "${INTERSHEET_REFS}" (at 308.4327 152.9556 0)
      (effects (font (size 1.27 1.27)) (justify right) hide)
    )
  )
  (global_label "FMC_IO_6_P" (shape input) (at 321.945 120.015 180) (fields_autoplaced)
    (effects (font (size 1.27 1.27)) (justify right))
    (property "Intersheetrefs" "${INTERSHEET_REFS}" (at 308.4932 119.9356 0)
      (effects (font (size 1.27 1.27)) (justify right) hide)
    )
  )
  (global_label "ETH_RXD0" (shape input) (at 64.77 117.475 180) (fields_autoplaced)
    (effects (font (size 1.27 1.27)) (justify right))
    (property "Intersheetrefs" "${INTERSHEET_REFS}" (at 5.08 0 0)
      (effects (font (size 1.27 1.27)) hide)
    )
  )
  (global_label "CB5" (shape input) (at 139.7 216.535 180) (fields_autoplaced)
    (effects (font (size 1.27 1.27)) (justify right))
    (property "Intersheetrefs" "${INTERSHEET_REFS}" (at 511.81 27.94 0)
      (effects (font (size 1.27 1.27)) (justify left) hide)
    )
  )
  (global_label "HR_DQ6" (shape input) (at 64.77 208.915 180) (fields_autoplaced)
    (effects (font (size 1.27 1.27)) (justify right))
    (property "Intersheetrefs" "${INTERSHEET_REFS}" (at 5.08 0 0)
      (effects (font (size 1.27 1.27)) hide)
    )
  )
  (global_label "HR_RST" (shape input) (at 64.77 163.195 180) (fields_autoplaced)
    (effects (font (size 1.27 1.27)) (justify right))
    (property "Intersheetrefs" "${INTERSHEET_REFS}" (at 5.08 0 0)
      (effects (font (size 1.27 1.27)) hide)
    )
  )
  (global_label "FMC_IO_13_P" (shape input) (at 321.945 155.575 180) (fields_autoplaced)
    (effects (font (size 1.27 1.27)) (justify right))
    (property "Intersheetrefs" "${INTERSHEET_REFS}" (at 308.4932 155.4956 0)
      (effects (font (size 1.27 1.27)) (justify right) hide)
    )
  )
  (global_label "CB0" (shape input) (at 139.7 186.055 180) (fields_autoplaced)
    (effects (font (size 1.27 1.27)) (justify right))
    (property "Intersheetrefs" "${INTERSHEET_REFS}" (at 511.81 -12.7 0)
      (effects (font (size 1.27 1.27)) (justify left) hide)
    )
  )
  (global_label "FMC_IO_16_P" (shape input) (at 321.945 170.815 180) (fields_autoplaced)
    (effects (font (size 1.27 1.27)) (justify right))
    (property "Intersheetrefs" "${INTERSHEET_REFS}" (at 308.4932 170.7356 0)
      (effects (font (size 1.27 1.27)) (justify right) hide)
    )
  )
  (global_label "3V3_SYS" (shape input) (at 321.945 86.995 180) (fields_autoplaced)
    (effects (font (size 1.27 1.27)) (justify right))
    (property "Intersheetrefs" "${INTERSHEET_REFS}" (at 259.08 369.57 0)
      (effects (font (size 1.27 1.27)) hide)
    )
  )
  (global_label "AUX_JTAG_TDI" (shape input) (at 241.3 147.955 180) (fields_autoplaced)
    (effects (font (size 1.27 1.27)) (justify right))
    (property "Intersheetrefs" "${INTERSHEET_REFS}" (at -12.065 -0.635 0)
      (effects (font (size 1.27 1.27)) hide)
    )
  )
  (global_label "FMC_IO_5_N" (shape input) (at 321.945 117.475 180) (fields_autoplaced)
    (effects (font (size 1.27 1.27)) (justify right))
    (property "Intersheetrefs" "${INTERSHEET_REFS}" (at 308.4327 117.3956 0)
      (effects (font (size 1.27 1.27)) (justify right) hide)
    )
  )
  (global_label "DDR_PRESENCE" (shape input) (at 64.77 213.995 180) (fields_autoplaced)
    (effects (font (size 1.27 1.27)) (justify right))
    (property "Intersheetrefs" "${INTERSHEET_REFS}" (at 47.871 213.9156 0)
      (effects (font (size 1.27 1.27)) (justify right) hide)
    )
  )
  (global_label "HR_DQ5" (shape input) (at 64.77 193.675 180) (fields_autoplaced)
    (effects (font (size 1.27 1.27)) (justify right))
    (property "Intersheetrefs" "${INTERSHEET_REFS}" (at 5.08 0 0)
      (effects (font (size 1.27 1.27)) hide)
    )
  )
  (global_label "FPGA_VTT_CNTL" (shape input) (at 241.3 183.515 180) (fields_autoplaced)
    (effects (font (size 1.27 1.27)) (justify right))
    (property "Intersheetrefs" "${INTERSHEET_REFS}" (at 224.7034 183.4356 0)
      (effects (font (size 1.27 1.27)) (justify right) hide)
    )
  )
  (global_label "HR_DQ3" (shape input) (at 64.77 211.455 180) (fields_autoplaced)
    (effects (font (size 1.27 1.27)) (justify right))
    (property "Intersheetrefs" "${INTERSHEET_REFS}" (at 5.08 0 0)
      (effects (font (size 1.27 1.27)) hide)
    )
  )
  (global_label "CB7" (shape input) (at 139.7 175.895 180) (fields_autoplaced)
    (effects (font (size 1.27 1.27)) (justify right))
    (property "Intersheetrefs" "${INTERSHEET_REFS}" (at 511.81 5.08 0)
      (effects (font (size 1.27 1.27)) (justify left) hide)
    )
  )
  (global_label "ETH_RXD2" (shape input) (at 64.77 112.395 180) (fields_autoplaced)
    (effects (font (size 1.27 1.27)) (justify right))
    (property "Intersheetrefs" "${INTERSHEET_REFS}" (at 5.08 0 0)
      (effects (font (size 1.27 1.27)) hide)
    )
  )
  (global_label "FMC_IO_7_P" (shape input) (at 321.945 125.095 180) (fields_autoplaced)
    (effects (font (size 1.27 1.27)) (justify right))
    (property "Intersheetrefs" "${INTERSHEET_REFS}" (at 308.4932 125.0156 0)
      (effects (font (size 1.27 1.27)) (justify right) hide)
    )
  )
  (global_label "FMC_IO_24_P" (shape input) (at 321.945 211.455 180) (fields_autoplaced)
    (effects (font (size 1.27 1.27)) (justify right))
    (property "Intersheetrefs" "${INTERSHEET_REFS}" (at 308.4932 211.3756 0)
      (effects (font (size 1.27 1.27)) (justify right) hide)
    )
  )
  (global_label "FMC_IO_1_N" (shape input) (at 321.945 97.155 180) (fields_autoplaced)
    (effects (font (size 1.27 1.27)) (justify right))
    (property "Intersheetrefs" "${INTERSHEET_REFS}" (at 308.4327 97.0756 0)
      (effects (font (size 1.27 1.27)) (justify right) hide)
    )
  )
  (global_label "QSPI_DQ1" (shape input) (at 241.3 97.155 180) (fields_autoplaced)
    (effects (font (size 1.27 1.27)) (justify right))
    (property "Intersheetrefs" "${INTERSHEET_REFS}" (at -12.065 -0.635 0)
      (effects (font (size 1.27 1.27)) hide)
    )
  )
  (global_label "AUX_JTAG_TDO" (shape input) (at 241.3 117.475 180) (fields_autoplaced)
    (effects (font (size 1.27 1.27)) (justify right))
    (property "Intersheetrefs" "${INTERSHEET_REFS}" (at -12.065 -0.635 0)
      (effects (font (size 1.27 1.27)) hide)
    )
  )
  (global_label "FMC_IO_4_N" (shape input) (at 321.945 112.395 180) (fields_autoplaced)
    (effects (font (size 1.27 1.27)) (justify right))
    (property "Intersheetrefs" "${INTERSHEET_REFS}" (at 308.4327 112.3156 0)
      (effects (font (size 1.27 1.27)) (justify right) hide)
    )
  )
  (global_label "FMC_IO_21_N" (shape input) (at 321.945 198.755 180) (fields_autoplaced)
    (effects (font (size 1.27 1.27)) (justify right))
    (property "Intersheetrefs" "${INTERSHEET_REFS}" (at 308.4327 198.6756 0)
      (effects (font (size 1.27 1.27)) (justify right) hide)
    )
  )
  (global_label "FMC_IO_8_N" (shape input) (at 321.945 132.715 180) (fields_autoplaced)
    (effects (font (size 1.27 1.27)) (justify right))
    (property "Intersheetrefs" "${INTERSHEET_REFS}" (at 308.4327 132.6356 0)
      (effects (font (size 1.27 1.27)) (justify right) hide)
    )
  )
  (global_label "FMC_IO_18_N" (shape input) (at 321.945 183.515 180) (fields_autoplaced)
    (effects (font (size 1.27 1.27)) (justify right))
    (property "Intersheetrefs" "${INTERSHEET_REFS}" (at 308.4327 183.4356 0)
      (effects (font (size 1.27 1.27)) (justify right) hide)
    )
  )
  (global_label "FMC_IO_5_P" (shape input) (at 321.945 114.935 180) (fields_autoplaced)
    (effects (font (size 1.27 1.27)) (justify right))
    (property "Intersheetrefs" "${INTERSHEET_REFS}" (at 308.4932 114.8556 0)
      (effects (font (size 1.27 1.27)) (justify right) hide)
    )
  )
  (global_label "AUX_JTAG_TCK" (shape input) (at 241.3 122.555 180) (fields_autoplaced)
    (effects (font (size 1.27 1.27)) (justify right))
    (property "Intersheetrefs" "${INTERSHEET_REFS}" (at -12.065 -0.635 0)
      (effects (font (size 1.27 1.27)) hide)
    )
  )
  (global_label "HR_DQ1" (shape input) (at 64.77 206.375 180) (fields_autoplaced)
    (effects (font (size 1.27 1.27)) (justify right))
    (property "Intersheetrefs" "${INTERSHEET_REFS}" (at 5.08 0 0)
      (effects (font (size 1.27 1.27)) hide)
    )
  )
  (global_label "ETH_TXD0" (shape input) (at 64.77 132.715 180) (fields_autoplaced)
    (effects (font (size 1.27 1.27)) (justify right))
    (property "Intersheetrefs" "${INTERSHEET_REFS}" (at 5.08 0 0)
      (effects (font (size 1.27 1.27)) hide)
    )
  )
  (global_label "FMC_IO_24_N" (shape input) (at 321.945 213.995 180) (fields_autoplaced)
    (effects (font (size 1.27 1.27)) (justify right))
    (property "Intersheetrefs" "${INTERSHEET_REFS}" (at 308.4327 213.9156 0)
      (effects (font (size 1.27 1.27)) (justify right) hide)
    )
  )
  (global_label "ETH_RXD3" (shape input) (at 64.77 102.235 180) (fields_autoplaced)
    (effects (font (size 1.27 1.27)) (justify right))
    (property "Intersheetrefs" "${INTERSHEET_REFS}" (at 5.08 0 0)
      (effects (font (size 1.27 1.27)) hide)
    )
  )
  (global_label "FMC_IO_14_P" (shape input) (at 321.945 160.655 180) (fields_autoplaced)
    (effects (font (size 1.27 1.27)) (justify right))
    (property "Intersheetrefs" "${INTERSHEET_REFS}" (at 308.4932 160.5756 0)
      (effects (font (size 1.27 1.27)) (justify right) hide)
    )
  )
  (global_label "UART0_RX" (shape input) (at 241.3 175.895 180) (fields_autoplaced)
    (effects (font (size 1.27 1.27)) (justify right))
    (property "Intersheetrefs" "${INTERSHEET_REFS}" (at -12.065 -0.635 0)
      (effects (font (size 1.27 1.27)) hide)
    )
  )
  (global_label "DQS17_N" (shape input) (at 139.7 198.755 180) (fields_autoplaced)
    (effects (font (size 1.27 1.27)) (justify right))
    (property "Intersheetrefs" "${INTERSHEET_REFS}" (at 128.8487 198.6756 0)
      (effects (font (size 1.27 1.27)) (justify right) hide)
    )
  )
  (global_label "SDA_3V3" (shape input) (at 241.3 114.935 180) (fields_autoplaced)
    (effects (font (size 1.27 1.27)) (justify right))
    (property "Intersheetrefs" "${INTERSHEET_REFS}" (at -12.065 -0.635 0)
      (effects (font (size 1.27 1.27)) hide)
    )
  )
  (global_label "QSPI_DQ3" (shape input) (at 241.3 102.235 180) (fields_autoplaced)
    (effects (font (size 1.27 1.27)) (justify right))
    (property "Intersheetrefs" "${INTERSHEET_REFS}" (at -12.065 -0.635 0)
      (effects (font (size 1.27 1.27)) hide)
    )
  )
  (global_label "QSPI_DQ0" (shape input) (at 241.3 94.615 180) (fields_autoplaced)
    (effects (font (size 1.27 1.27)) (justify right))
    (property "Intersheetrefs" "${INTERSHEET_REFS}" (at -12.065 -0.635 0)
      (effects (font (size 1.27 1.27)) hide)
    )
  )
  (global_label "FMC_IO_20_P" (shape input) (at 321.945 191.135 180) (fields_autoplaced)
    (effects (font (size 1.27 1.27)) (justify right))
    (property "Intersheetrefs" "${INTERSHEET_REFS}" (at 308.4932 191.0556 0)
      (effects (font (size 1.27 1.27)) (justify right) hide)
    )
  )
  (global_label "FMC_IO_15_P" (shape input) (at 321.945 165.735 180) (fields_autoplaced)
    (effects (font (size 1.27 1.27)) (justify right))
    (property "Intersheetrefs" "${INTERSHEET_REFS}" (at 308.4932 165.6556 0)
      (effects (font (size 1.27 1.27)) (justify right) hide)
    )
  )
  (global_label "PRSNT_M2C" (shape input) (at 241.3 153.035 180) (fields_autoplaced)
    (effects (font (size 1.27 1.27)) (justify right))
    (property "Intersheetrefs" "${INTERSHEET_REFS}" (at 228.0296 152.9556 0)
      (effects (font (size 1.27 1.27)) (justify right) hide)
    )
  )
  (global_label "ETH_MDIO" (shape input) (at 64.77 135.255 180) (fields_autoplaced)
    (effects (font (size 1.27 1.27)) (justify right))
    (property "Intersheetrefs" "${INTERSHEET_REFS}" (at 5.08 0 0)
      (effects (font (size 1.27 1.27)) hide)
    )
  )
  (global_label "FMC_IO_8_P" (shape input) (at 321.945 130.175 180) (fields_autoplaced)
    (effects (font (size 1.27 1.27)) (justify right))
    (property "Intersheetrefs" "${INTERSHEET_REFS}" (at 308.4932 130.0956 0)
      (effects (font (size 1.27 1.27)) (justify right) hide)
    )
  )
  (global_label "HOT_SWAP_BUTTON" (shape input) (at 241.3 140.335 180) (fields_autoplaced)
    (effects (font (size 1.27 1.27)) (justify right))
    (property "Intersheetrefs" "${INTERSHEET_REFS}" (at 221.1958 140.4144 0)
      (effects (font (size 1.27 1.27)) (justify right) hide)
    )
  )
  (global_label "FMC_IO_10_N" (shape input) (at 321.945 142.875 180) (fields_autoplaced)
    (effects (font (size 1.27 1.27)) (justify right))
    (property "Intersheetrefs" "${INTERSHEET_REFS}" (at 308.4327 142.7956 0)
      (effects (font (size 1.27 1.27)) (justify right) hide)
    )
  )
  (global_label "ETH_RSTN" (shape input) (at 64.77 158.115 180) (fields_autoplaced)
    (effects (font (size 1.27 1.27)) (justify right))
    (property "Intersheetrefs" "${INTERSHEET_REFS}" (at 5.08 0 0)
      (effects (font (size 1.27 1.27)) hide)
    )
  )
  (global_label "QSPI_DQ2" (shape input) (at 241.3 99.695 180) (fields_autoplaced)
    (effects (font (size 1.27 1.27)) (justify right))
    (property "Intersheetrefs" "${INTERSHEET_REFS}" (at -12.065 -0.635 0)
      (effects (font (size 1.27 1.27)) hide)
    )
  )
  (global_label "3V3_SYS" (shape input) (at 241.3 86.995 180) (fields_autoplaced)
    (effects (font (size 1.27 1.27)) (justify right))
    (property "Intersheetrefs" "${INTERSHEET_REFS}" (at 178.435 369.57 0)
      (effects (font (size 1.27 1.27)) hide)
    )
  )
  (global_label "HOT_SWAP_RED" (shape input) (at 241.3 135.255 180) (fields_autoplaced)
    (effects (font (size 1.27 1.27)) (justify right))
    (property "Intersheetrefs" "${INTERSHEET_REFS}" (at 224.7034 135.1756 0)
      (effects (font (size 1.27 1.27)) (justify right) hide)
    )
  )
  (global_label "DQS8_N" (shape input) (at 139.7 137.795 180) (fields_autoplaced)
    (effects (font (size 1.27 1.27)) (justify right))
    (property "Intersheetrefs" "${INTERSHEET_REFS}" (at 130.0582 137.7156 0)
      (effects (font (size 1.27 1.27)) (justify right) hide)
    )
  )
  (global_label "FMC_IO_23_P" (shape input) (at 321.945 206.375 180) (fields_autoplaced)
    (effects (font (size 1.27 1.27)) (justify right))
    (property "Intersheetrefs" "${INTERSHEET_REFS}" (at 308.4932 206.2956 0)
      (effects (font (size 1.27 1.27)) (justify right) hide)
    )
  )
  (global_label "HR_DQ7" (shape input) (at 64.77 173.355 180) (fields_autoplaced)
    (effects (font (size 1.27 1.27)) (justify right))
    (property "Intersheetrefs" "${INTERSHEET_REFS}" (at 5.08 0 0)
      (effects (font (size 1.27 1.27)) hide)
    )
  )
  (global_label "FMC_IO_22_P" (shape input) (at 321.945 201.295 180) (fields_autoplaced)
    (effects (font (size 1.27 1.27)) (justify right))
    (property "Intersheetrefs" "${INTERSHEET_REFS}" (at 308.4932 201.2156 0)
      (effects (font (size 1.27 1.27)) (justify right) hide)
    )
  )
  (global_label "HR_RW" (shape input) (at 64.77 170.815 180) (fields_autoplaced)
    (effects (font (size 1.27 1.27)) (justify right))
    (property "Intersheetrefs" "${INTERSHEET_REFS}" (at 5.08 0 0)
      (effects (font (size 1.27 1.27)) hide)
    )
  )
  (global_label "FMC_IO_17_N" (shape input) (at 321.945 178.435 180) (fields_autoplaced)
    (effects (font (size 1.27 1.27)) (justify right))
    (property "Intersheetrefs" "${INTERSHEET_REFS}" (at 308.4327 178.3556 0)
      (effects (font (size 1.27 1.27)) (justify right) hide)
    )
  )
  (global_label "CB4" (shape input) (at 139.7 208.915 180) (fields_autoplaced)
    (effects (font (size 1.27 1.27)) (justify right))
    (property "Intersheetrefs" "${INTERSHEET_REFS}" (at 511.81 7.62 0)
      (effects (font (size 1.27 1.27)) (justify left) hide)
    )
  )
  (global_label "FMC_IO_2_P" (shape input) (at 321.945 99.695 180) (fields_autoplaced)
    (effects (font (size 1.27 1.27)) (justify right))
    (property "Intersheetrefs" "${INTERSHEET_REFS}" (at 308.4932 99.6156 0)
      (effects (font (size 1.27 1.27)) (justify right) hide)
    )
  )
  (global_label "FMC_IO_4_P" (shape input) (at 321.945 109.855 180) (fields_autoplaced)
    (effects (font (size 1.27 1.27)) (justify right))
    (property "Intersheetrefs" "${INTERSHEET_REFS}" (at 308.4932 109.7756 0)
      (effects (font (size 1.27 1.27)) (justify right) hide)
    )
  )
  (global_label "CB2" (shape input) (at 139.7 160.655 180) (fields_autoplaced)
    (effects (font (size 1.27 1.27)) (justify right))
    (property "Intersheetrefs" "${INTERSHEET_REFS}" (at 511.81 -7.62 0)
      (effects (font (size 1.27 1.27)) (justify left) hide)
    )
  )
  (global_label "FMC_IO_21_P" (shape input) (at 321.945 196.215 180) (fields_autoplaced)
    (effects (font (size 1.27 1.27)) (justify right))
    (property "Intersheetrefs" "${INTERSHEET_REFS}" (at 308.4932 196.1356 0)
      (effects (font (size 1.27 1.27)) (justify right) hide)
    )
  )
  (global_label "FMC_IO_19_N" (shape input) (at 321.945 188.595 180) (fields_autoplaced)
    (effects (font (size 1.27 1.27)) (justify right))
    (property "Intersheetrefs" "${INTERSHEET_REFS}" (at 308.4327 188.5156 0)
      (effects (font (size 1.27 1.27)) (justify right) hide)
    )
  )
  (global_label "ETH_REF_CLK" (shape input) (at 64.77 145.415 180) (fields_autoplaced)
    (effects (font (size 1.27 1.27)) (justify right))
    (property "Intersheetrefs" "${INTERSHEET_REFS}" (at 5.08 0 0)
      (effects (font (size 1.27 1.27)) hide)
    )
  )
  (global_label "HR_CS" (shape input) (at 64.77 137.795 180) (fields_autoplaced)
    (effects (font (size 1.27 1.27)) (justify right))
    (property "Intersheetrefs" "${INTERSHEET_REFS}" (at 5.08 0 0)
      (effects (font (size 1.27 1.27)) hide)
    )
  )
  (global_label "FPGA_POWER_CYCLE" (shape input) (at 241.3 173.355 180) (fields_autoplaced)
    (effects (font (size 1.27 1.27)) (justify right))
    (property "Intersheetrefs" "${INTERSHEET_REFS}" (at 220.0468 173.2756 0)
      (effects (font (size 1.27 1.27)) (justify right) hide)
    )
  )
  (global_label "EMCCLK" (shape input) (at 241.3 107.315 180) (fields_autoplaced)
    (effects (font (size 1.27 1.27)) (justify right))
    (property "Intersheetrefs" "${INTERSHEET_REFS}" (at -12.065 -0.635 0)
      (effects (font (size 1.27 1.27)) hide)
    )
  )
  (global_label "HR_DQ0" (shape input) (at 64.77 201.295 180) (fields_autoplaced)
    (effects (font (size 1.27 1.27)) (justify right))
    (property "Intersheetrefs" "${INTERSHEET_REFS}" (at 5.08 0 0)
      (effects (font (size 1.27 1.27)) hide)
    )
  )
  (global_label "USR_LED4" (shape input) (at 241.3 127.635 180) (fields_autoplaced)
    (effects (font (size 1.27 1.27)) (justify right))
    (property "Intersheetrefs" "${INTERSHEET_REFS}" (at -12.065 -0.635 0)
      (effects (font (size 1.27 1.27)) hide)
    )
  )
  (global_label "FMC_IO_0" (shape input) (at 321.945 92.075 180) (fields_autoplaced)
    (effects (font (size 1.27 1.27)) (justify right))
    (property "Intersheetrefs" "${INTERSHEET_REFS}" (at 310.7308 91.9956 0)
      (effects (font (size 1.27 1.27)) (justify right) hide)
    )
  )
  (global_label "3V3_SYS" (shape input) (at 64.77 86.995 180) (fields_autoplaced)
    (effects (font (size 1.27 1.27)) (justify right))
    (property "Intersheetrefs" "${INTERSHEET_REFS}" (at 2.54 175.895 0)
      (effects (font (size 1.27 1.27)) hide)
    )
  )
  (global_label "ETH_TX_EN" (shape input) (at 64.77 109.855 180) (fields_autoplaced)
    (effects (font (size 1.27 1.27)) (justify right))
    (property "Intersheetrefs" "${INTERSHEET_REFS}" (at 5.08 0 0)
      (effects (font (size 1.27 1.27)) hide)
    )
  )
  (global_label "FMC_IO_10_P" (shape input) (at 321.945 140.335 180) (fields_autoplaced)
    (effects (font (size 1.27 1.27)) (justify right))
    (property "Intersheetrefs" "${INTERSHEET_REFS}" (at 308.4932 140.2556 0)
      (effects (font (size 1.27 1.27)) (justify right) hide)
    )
  )
  (global_label "FMC_IO_11_P" (shape input) (at 321.945 145.415 180) (fields_autoplaced)
    (effects (font (size 1.27 1.27)) (justify right))
    (property "Intersheetrefs" "${INTERSHEET_REFS}" (at 308.4932 145.3356 0)
      (effects (font (size 1.27 1.27)) (justify right) hide)
    )
  )
  (global_label "ETH_TXD3" (shape input) (at 64.77 168.275 180) (fields_autoplaced)
    (effects (font (size 1.27 1.27)) (justify right))
    (property "Intersheetrefs" "${INTERSHEET_REFS}" (at 5.08 0 0)
      (effects (font (size 1.27 1.27)) hide)
    )
  )
  (global_label "SCL_3V3" (shape input) (at 241.3 165.735 180) (fields_autoplaced)
    (effects (font (size 1.27 1.27)) (justify right))
    (property "Intersheetrefs" "${INTERSHEET_REFS}" (at -12.065 -0.635 0)
      (effects (font (size 1.27 1.27)) hide)
    )
  )
  (global_label "UART1_RX" (shape input) (at 241.3 112.395 180) (fields_autoplaced)
    (effects (font (size 1.27 1.27)) (justify right))
    (property "Intersheetrefs" "${INTERSHEET_REFS}" (at -12.065 -0.635 0)
      (effects (font (size 1.27 1.27)) hide)
    )
  )
  (global_label "DQS17_P" (shape input) (at 139.7 196.215 180) (fields_autoplaced)
    (effects (font (size 1.27 1.27)) (justify right))
    (property "Intersheetrefs" "${INTERSHEET_REFS}" (at 128.9091 196.1356 0)
      (effects (font (size 1.27 1.27)) (justify right) hide)
    )
  )
  (global_label "USR_LED2" (shape input) (at 241.3 130.175 180) (fields_autoplaced)
    (effects (font (size 1.27 1.27)) (justify right))
    (property "Intersheetrefs" "${INTERSHEET_REFS}" (at -12.065 -0.635 0)
      (effects (font (size 1.27 1.27)) hide)
    )
  )
  (global_label "FMC_IO_9_N" (shape input) (at 321.945 137.795 180) (fields_autoplaced)
    (effects (font (size 1.27 1.27)) (justify right))
    (property "Intersheetrefs" "${INTERSHEET_REFS}" (at 308.4327 137.7156 0)
      (effects (font (size 1.27 1.27)) (justify right) hide)
    )
  )
  (global_label "FMC_IO_12_P" (shape input) (at 321.945 150.495 180) (fields_autoplaced)
    (effects (font (size 1.27 1.27)) (justify right))
    (property "Intersheetrefs" "${INTERSHEET_REFS}" (at 308.4932 150.4156 0)
      (effects (font (size 1.27 1.27)) (justify right) hide)
    )
  )
  (global_label "CB1" (shape input) (at 139.7 206.375 180) (fields_autoplaced)
    (effects (font (size 1.27 1.27)) (justify right))
    (property "Intersheetrefs" "${INTERSHEET_REFS}" (at 511.81 10.16 0)
      (effects (font (size 1.27 1.27)) (justify left) hide)
    )
  )
  (global_label "ETH_TXD1" (shape input) (at 64.77 142.875 180) (fields_autoplaced)
    (effects (font (size 1.27 1.27)) (justify right))
    (property "Intersheetrefs" "${INTERSHEET_REFS}" (at 5.08 0 0)
      (effects (font (size 1.27 1.27)) hide)
    )
  )
  (global_label "USR_LED1" (shape input) (at 241.3 125.095 180) (fields_autoplaced)
    (effects (font (size 1.27 1.27)) (justify right))
    (property "Intersheetrefs" "${INTERSHEET_REFS}" (at -12.065 -0.635 0)
      (effects (font (size 1.27 1.27)) hide)
    )
  )
  (global_label "FMC_IO_3_P" (shape input) (at 321.945 104.775 180) (fields_autoplaced)
    (effects (font (size 1.27 1.27)) (justify right))
    (property "Intersheetrefs" "${INTERSHEET_REFS}" (at 308.4932 104.6956 0)
      (effects (font (size 1.27 1.27)) (justify right) hide)
    )
  )
  (global_label "FMC_IO_9_P" (shape input) (at 321.945 135.255 180) (fields_autoplaced)
    (effects (font (size 1.27 1.27)) (justify right))
    (property "Intersheetrefs" "${INTERSHEET_REFS}" (at 308.4932 135.1756 0)
      (effects (font (size 1.27 1.27)) (justify right) hide)
    )
  )
  (global_label "ETH_TXD2" (shape input) (at 64.77 155.575 180) (fields_autoplaced)
    (effects (font (size 1.27 1.27)) (justify right))
    (property "Intersheetrefs" "${INTERSHEET_REFS}" (at 5.08 0 0)
      (effects (font (size 1.27 1.27)) hide)
    )
  )
  (global_label "UART0_TX" (shape input) (at 241.3 178.435 180) (fields_autoplaced)
    (effects (font (size 1.27 1.27)) (justify right))
    (property "Intersheetrefs" "${INTERSHEET_REFS}" (at -12.065 -0.635 0)
      (effects (font (size 1.27 1.27)) hide)
    )
  )
  (global_label "FMC_IO_25" (shape input) (at 321.945 216.535 180) (fields_autoplaced)
    (effects (font (size 1.27 1.27)) (justify right))
    (property "Intersheetrefs" "${INTERSHEET_REFS}" (at 309.5213 216.4556 0)
      (effects (font (size 1.27 1.27)) (justify right) hide)
    )
  )
  (global_label "FMC_IO_20_N" (shape input) (at 321.945 193.675 180) (fields_autoplaced)
    (effects (font (size 1.27 1.27)) (justify right))
    (property "Intersheetrefs" "${INTERSHEET_REFS}" (at 308.4327 193.5956 0)
      (effects (font (size 1.27 1.27)) (justify right) hide)
    )
  )
  (global_label "CB3" (shape input) (at 139.7 178.435 180) (fields_autoplaced)
    (effects (font (size 1.27 1.27)) (justify right))
    (property "Intersheetrefs" "${INTERSHEET_REFS}" (at 511.81 17.78 0)
      (effects (font (size 1.27 1.27)) (justify left) hide)
    )
  )
  (global_label "AUX_JTAG_RST" (shape input) (at 241.3 170.815 180) (fields_autoplaced)
    (effects (font (size 1.27 1.27)) (justify right))
    (property "Intersheetrefs" "${INTERSHEET_REFS}" (at -12.065 -0.635 0)
      (effects (font (size 1.27 1.27)) hide)
    )
  )
  (global_label "FMC_IO_3_N" (shape input) (at 321.945 107.315 180) (fields_autoplaced)
    (effects (font (size 1.27 1.27)) (justify right))
    (property "Intersheetrefs" "${INTERSHEET_REFS}" (at 308.4327 107.2356 0)
      (effects (font (size 1.27 1.27)) (justify right) hide)
    )
  )
  (global_label "FMC_IO_18_P" (shape input) (at 321.945 180.975 180) (fields_autoplaced)
    (effects (font (size 1.27 1.27)) (justify right))
    (property "Intersheetrefs" "${INTERSHEET_REFS}" (at 308.4932 180.8956 0)
      (effects (font (size 1.27 1.27)) (justify right) hide)
    )
  )
  (global_label "ETH_SEL" (shape input) (at 64.77 99.695 180) (fields_autoplaced)
    (effects (font (size 1.27 1.27)) (justify right))
    (property "Intersheetrefs" "${INTERSHEET_REFS}" (at 54.6444 99.6156 0)
      (effects (font (size 1.27 1.27)) (justify right) hide)
    )
  )
  (global_label "ETH_RX_CLK" (shape input) (at 64.77 150.495 180) (fields_autoplaced)
    (effects (font (size 1.27 1.27)) (justify right))
    (property "Intersheetrefs" "${INTERSHEET_REFS}" (at 5.08 0 0)
      (effects (font (size 1.27 1.27)) hide)
    )
  )
  (global_label "UART1_TX" (shape input) (at 241.3 109.855 180) (fields_autoplaced)
    (effects (font (size 1.27 1.27)) (justify right))
    (property "Intersheetrefs" "${INTERSHEET_REFS}" (at -12.065 -0.635 0)
      (effects (font (size 1.27 1.27)) hide)
    )
  )
  (global_label "FMC_SDA_3V3" (shape input) (at 241.3 160.655 180) (fields_autoplaced)
    (effects (font (size 1.27 1.27)) (justify right))
    (property "Intersheetrefs" "${INTERSHEET_REFS}" (at 226.1548 160.5756 0)
      (effects (font (size 1.27 1.27)) (justify right) hide)
    )
  )
  (global_label "FMC_IO_19_P" (shape input) (at 321.945 186.055 180) (fields_autoplaced)
    (effects (font (size 1.27 1.27)) (justify right))
    (property "Intersheetrefs" "${INTERSHEET_REFS}" (at 308.4932 185.9756 0)
      (effects (font (size 1.27 1.27)) (justify right) hide)
    )
  )
  (global_label "CLK_DIR" (shape input) (at 241.3 163.195 180) (fields_autoplaced)
    (effects (font (size 1.27 1.27)) (justify right))
    (property "Intersheetrefs" "${INTERSHEET_REFS}" (at 231.2953 163.1156 0)
      (effects (font (size 1.27 1.27)) (justify right) hide)
    )
  )
  (global_label "FCS_B" (shape input) (at 241.3 120.015 180) (fields_autoplaced)
    (effects (font (size 1.27 1.27)) (justify right))
    (property "Intersheetrefs" "${INTERSHEET_REFS}" (at -12.065 -0.635 0)
      (effects (font (size 1.27 1.27)) hide)
    )
  )
  (global_label "ETH_TX_CLK" (shape input) (at 64.77 153.035 180) (fields_autoplaced)
    (effects (font (size 1.27 1.27)) (justify right))
    (property "Intersheetrefs" "${INTERSHEET_REFS}" (at 5.08 0 0)
      (effects (font (size 1.27 1.27)) hide)
    )
  )
  (global_label "FMC_IO_23_N" (shape input) (at 321.945 208.915 180) (fields_autoplaced)
    (effects (font (size 1.27 1.27)) (justify right))
    (property "Intersheetrefs" "${INTERSHEET_REFS}" (at 308.4327 208.8356 0)
      (effects (font (size 1.27 1.27)) (justify right) hide)
    )
  )
  (global_label "HR_DQ4" (shape input) (at 64.77 203.835 180) (fields_autoplaced)
    (effects (font (size 1.27 1.27)) (justify right))
    (property "Intersheetrefs" "${INTERSHEET_REFS}" (at 5.08 0 0)
      (effects (font (size 1.27 1.27)) hide)
    )
  )
  (global_label "FMC_SCL_3V3" (shape input) (at 241.3 198.755 180) (fields_autoplaced)
    (effects (font (size 1.27 1.27)) (justify right))
    (property "Intersheetrefs" "${INTERSHEET_REFS}" (at 226.2153 198.6756 0)
      (effects (font (size 1.27 1.27)) (justify right) hide)
    )
  )
  (global_label "FMC_IO_6_N" (shape input) (at 321.945 122.555 180) (fields_autoplaced)
    (effects (font (size 1.27 1.27)) (justify right))
    (property "Intersheetrefs" "${INTERSHEET_REFS}" (at 308.4327 122.4756 0)
      (effects (font (size 1.27 1.27)) (justify right) hide)
    )
  )
  (global_label "USR_LED5" (shape input) (at 241.3 137.795 180) (fields_autoplaced)
    (effects (font (size 1.27 1.27)) (justify right))
    (property "Intersheetrefs" "${INTERSHEET_REFS}" (at -12.065 -0.635 0)
      (effects (font (size 1.27 1.27)) hide)
    )
  )
  (global_label "FMC_IO_14_N" (shape input) (at 321.945 163.195 180) (fields_autoplaced)
    (effects (font (size 1.27 1.27)) (justify right))
    (property "Intersheetrefs" "${INTERSHEET_REFS}" (at 308.4327 163.1156 0)
      (effects (font (size 1.27 1.27)) (justify right) hide)
    )
  )
  (global_label "FMC_IO_13_N" (shape input) (at 321.945 158.115 180) (fields_autoplaced)
    (effects (font (size 1.27 1.27)) (justify right))
    (property "Intersheetrefs" "${INTERSHEET_REFS}" (at 308.4327 158.0356 0)
      (effects (font (size 1.27 1.27)) (justify right) hide)
    )
  )
  (global_label "HR_CKN" (shape input) (at 64.77 198.755 180) (fields_autoplaced)
    (effects (font (size 1.27 1.27)) (justify right))
    (property "Intersheetrefs" "${INTERSHEET_REFS}" (at 5.08 0 0)
      (effects (font (size 1.27 1.27)) hide)
    )
  )
  (global_label "DQS8_P" (shape input) (at 139.7 135.255 180) (fields_autoplaced)
    (effects (font (size 1.27 1.27)) (justify right))
    (property "Intersheetrefs" "${INTERSHEET_REFS}" (at 130.1187 135.1756 0)
      (effects (font (size 1.27 1.27)) (justify right) hide)
    )
  )
  (global_label "HOT_SWAP_YELLOW" (shape input) (at 241.3 132.715 180) (fields_autoplaced)
    (effects (font (size 1.27 1.27)) (justify right))
    (property "Intersheetrefs" "${INTERSHEET_REFS}" (at 221.3168 132.6356 0)
      (effects (font (size 1.27 1.27)) (justify right) hide)
    )
  )
  (global_label "FMC_IO_16_N" (shape input) (at 321.945 173.355 180) (fields_autoplaced)
    (effects (font (size 1.27 1.27)) (justify right))
    (property "Intersheetrefs" "${INTERSHEET_REFS}" (at 308.4327 173.2756 0)
      (effects (font (size 1.27 1.27)) (justify right) hide)
    )
  )
  (global_label "AUX_JTAG_TMS" (shape input) (at 241.3 168.275 180) (fields_autoplaced)
    (effects (font (size 1.27 1.27)) (justify right))
    (property "Intersheetrefs" "${INTERSHEET_REFS}" (at -12.065 -0.635 0)
      (effects (font (size 1.27 1.27)) hide)
    )
  )
  (global_label "FMC_IO_7_N" (shape input) (at 321.945 127.635 180) (fields_autoplaced)
    (effects (font (size 1.27 1.27)) (justify right))
    (property "Intersheetrefs" "${INTERSHEET_REFS}" (at 308.4327 127.5556 0)
      (effects (font (size 1.27 1.27)) (justify right) hide)
    )
  )
  (global_label "FMC_IO_22_N" (shape input) (at 321.945 203.835 180) (fields_autoplaced)
    (effects (font (size 1.27 1.27)) (justify right))
    (property "Intersheetrefs" "${INTERSHEET_REFS}" (at 308.4327 203.7556 0)
      (effects (font (size 1.27 1.27)) (justify right) hide)
    )
  )
  (global_label "ETH_MDC" (shape input) (at 64.77 125.095 180) (fields_autoplaced)
    (effects (font (size 1.27 1.27)) (justify right))
    (property "Intersheetrefs" "${INTERSHEET_REFS}" (at 5.08 0 0)
      (effects (font (size 1.27 1.27)) hide)
    )
  )
  (global_label "FMC_IO_1_P" (shape input) (at 321.945 94.615 180) (fields_autoplaced)
    (effects (font (size 1.27 1.27)) (justify right))
    (property "Intersheetrefs" "${INTERSHEET_REFS}" (at 308.4932 94.5356 0)
      (effects (font (size 1.27 1.27)) (justify right) hide)
    )
  )
  (global_label "HR_DQ2" (shape input) (at 64.77 191.135 180) (fields_autoplaced)
    (effects (font (size 1.27 1.27)) (justify right))
    (property "Intersheetrefs" "${INTERSHEET_REFS}" (at 5.08 0 0)
      (effects (font (size 1.27 1.27)) hide)
    )
  )

  (symbol (lib_id "antmicroMicrocontrollers:XC7K160T-FFG676") (at 68.58 86.995 0) (unit 1)
    (in_bom yes) (on_board yes) (dnp no) (fields_autoplaced)
    (property "Reference" "U15" (at 87.63 78.74 0)
      (effects (font (size 1.27 1.27)))
    )
    (property "Value" "XC7K160T-FFG676" (at 87.63 81.28 0)
      (effects (font (size 1.27 1.27) (thickness 0.15)))
    )
    (property "Footprint" "antmicro-footprints:BGA-676_27x27mm_Layout26x26_P1X1mm" (at 137.16 89.535 0)
      (effects (font (size 1.27 1.27) (thickness 0.15)) (justify left bottom) hide)
    )
    (property "Datasheet" "https://docs.xilinx.com/v/u/en-US/ds180_7Series_Overview" (at 137.16 92.075 0)
      (effects (font (size 1.27 1.27) (thickness 0.15)) (justify left bottom) hide)
    )
    (property "MPN" "XC7K160T-FFG676" (at 68.58 86.995 0)
      (effects (font (size 1.27 1.27)) hide)
    )
    (property "Author" "Antmicro" (at 137.16 94.615 0)
      (effects (font (size 1.27 1.27) (thickness 0.15)) (justify left bottom) hide)
    )
    (property "License" "Apache-2.0" (at 137.16 97.155 0)
      (effects (font (size 1.27 1.27) (thickness 0.15)) (justify left bottom) hide)
    )
    (property "Manufacturer" "AMD-Xilinx" (at 68.58 86.995 0)
      (effects (font (size 1.27 1.27)) hide)
    )
    (pin "AA21")
    (pin "AA22")
    (pin "AA23")
    (pin "AA24")
    (pin "AA25")
    (pin "AB21")
    (pin "AB22")
    (pin "AB24")
    (pin "AB25")
    (pin "AB26")
    (pin "AC21")
    (pin "AC22")
    (pin "AC23")
    (pin "AC24")
    (pin "AC25")
    (pin "AC26")
    (pin "AD21")
    (pin "AD22")
    (pin "AD23")
    (pin "AD24")
    (pin "AD25")
    (pin "AD26")
    (pin "AE21")
    (pin "AE22")
    (pin "AE23")
    (pin "AE25")
    (pin "AE26")
    (pin "AF22")
    (pin "AF23")
    (pin "AF24")
    (pin "AF25")
    (pin "AF26")
    (pin "U21")
    (pin "U22")
    (pin "U23")
    (pin "U24")
    (pin "U25")
    (pin "U26")
    (pin "V20")
    (pin "V21")
    (pin "V22")
    (pin "V23")
    (pin "V24")
    (pin "V26")
    (pin "W20")
    (pin "W21")
    (pin "W23")
    (pin "W24")
    (pin "W25")
    (pin "W26")
    (pin "Y20")
    (pin "Y21")
    (pin "Y22")
    (pin "Y23")
    (pin "Y24")
    (pin "Y25")
    (pin "Y26")
    (pin "K24")
    (pin "K25")
    (pin "K26")
    (pin "L24")
    (pin "L25")
    (pin "M19")
    (pin "M20")
    (pin "M21")
    (pin "M22")
    (pin "M24")
    (pin "M25")
    (pin "M26")
    (pin "N16")
    (pin "N17")
    (pin "N18")
    (pin "N19")
    (pin "N21")
    (pin "N22")
    (pin "N23")
    (pin "N24")
    (pin "N25")
    (pin "N26")
    (pin "P16")
    (pin "P18")
    (pin "P19")
    (pin "P20")
    (pin "P21")
    (pin "P22")
    (pin "P23")
    (pin "P24")
    (pin "P25")
    (pin "P26")
    (pin "R16")
    (pin "R17")
    (pin "R18")
    (pin "R19")
    (pin "R20")
    (pin "R21")
    (pin "R22")
    (pin "R23")
    (pin "R25")
    (pin "R26")
    (pin "T16")
    (pin "T17")
    (pin "T18")
    (pin "T19")
    (pin "T20")
    (pin "T22")
    (pin "T23")
    (pin "T24")
    (pin "T25")
    (pin "T26")
    (pin "U16")
    (pin "U17")
    (pin "U19")
    (pin "U20")
    (pin "A20")
    (pin "A21")
    (pin "A22")
    (pin "A23")
    (pin "A24")
    (pin "A25")
    (pin "B20")
    (pin "B21")
    (pin "B22")
    (pin "B24")
    (pin "B25")
    (pin "B26")
    (pin "C21")
    (pin "C22")
    (pin "C23")
    (pin "C24")
    (pin "C25")
    (pin "C26")
    (pin "D21")
    (pin "D22")
    (pin "D23")
    (pin "D24")
    (pin "D25")
    (pin "D26")
    (pin "E21")
    (pin "E22")
    (pin "E23")
    (pin "E25")
    (pin "E26")
    (pin "F22")
    (pin "F23")
    (pin "F24")
    (pin "F25")
    (pin "F26")
    (pin "G21")
    (pin "G22")
    (pin "G23")
    (pin "G24")
    (pin "G25")
    (pin "G26")
    (pin "H21")
    (pin "H22")
    (pin "H23")
    (pin "H24")
    (pin "H26")
    (pin "J21")
    (pin "J23")
    (pin "J24")
    (pin "J25")
    (pin "J26")
    (pin "K21")
    (pin "K22")
    (pin "K23")
    (pin "L21")
    (pin "L22")
    (pin "L23")
    (pin "A17")
    (pin "A18")
    (pin "A19")
    (pin "B16")
    (pin "B17")
    (pin "B18")
    (pin "B19")
    (pin "C16")
    (pin "C17")
    (pin "C18")
    (pin "C19")
    (pin "D15")
    (pin "D16")
    (pin "D18")
    (pin "D19")
    (pin "D20")
    (pin "E15")
    (pin "E16")
    (pin "E17")
    (pin "E18")
    (pin "E19")
    (pin "E20")
    (pin "F15")
    (pin "F16")
    (pin "F17")
    (pin "F18")
    (pin "F19")
    (pin "F20")
    (pin "G15")
    (pin "G16")
    (pin "G17")
    (pin "G19")
    (pin "G20")
    (pin "H16")
    (pin "H17")
    (pin "H18")
    (pin "H19")
    (pin "H20")
    (pin "J15")
    (pin "J16")
    (pin "J17")
    (pin "J18")
    (pin "J19")
    (pin "J20")
    (pin "K15")
    (pin "K16")
    (pin "K17")
    (pin "K18")
    (pin "K20")
    (pin "L17")
    (pin "L18")
    (pin "L19")
    (pin "L20")
    (pin "M16")
    (pin "M17")
    (pin "M18")
    (pin "A10")
    (pin "A11")
    (pin "A12")
    (pin "A13")
    (pin "A14")
    (pin "A15")
    (pin "A8")
    (pin "A9")
    (pin "B10")
    (pin "B11")
    (pin "B12")
    (pin "B14")
    (pin "B15")
    (pin "B8")
    (pin "B9")
    (pin "C11")
    (pin "C12")
    (pin "C13")
    (pin "C14")
    (pin "C15")
    (pin "C9")
    (pin "D10")
    (pin "D11")
    (pin "D12")
    (pin "D13")
    (pin "D14")
    (pin "D8")
    (pin "D9")
    (pin "E10")
    (pin "E11")
    (pin "E12")
    (pin "E13")
    (pin "E9")
    (pin "F10")
    (pin "F12")
    (pin "F13")
    (pin "F14")
    (pin "F8")
    (pin "F9")
    (pin "G10")
    (pin "G11")
    (pin "G12")
    (pin "G13")
    (pin "G14")
    (pin "G9")
    (pin "H10")
    (pin "H11")
    (pin "H12")
    (pin "H13")
    (pin "H14")
    (pin "H8")
    (pin "H9")
    (pin "J10")
    (pin "J11")
    (pin "J13")
    (pin "J14")
    (pin "J8")
    (pin "AA14")
    (pin "AA15")
    (pin "AA17")
    (pin "AA18")
    (pin "AA19")
    (pin "AA20")
    (pin "AB14")
    (pin "AB15")
    (pin "AB16")
    (pin "AB17")
    (pin "AB18")
    (pin "AB19")
    (pin "AB20")
    (pin "AC14")
    (pin "AC15")
    (pin "AC16")
    (pin "AC17")
    (pin "AC18")
    (pin "AC19")
    (pin "AD14")
    (pin "AD15")
    (pin "AD16")
    (pin "AD18")
    (pin "AD19")
    (pin "AD20")
    (pin "AE15")
    (pin "AE16")
    (pin "AE17")
    (pin "AE18")
    (pin "AE19")
    (pin "AE20")
    (pin "AF14")
    (pin "AF15")
    (pin "AF16")
    (pin "AF17")
    (pin "AF18")
    (pin "AF19")
    (pin "AF20")
    (pin "V13")
    (pin "V14")
    (pin "V16")
    (pin "V17")
    (pin "V18")
    (pin "V19")
    (pin "W13")
    (pin "W14")
    (pin "W15")
    (pin "W16")
    (pin "W17")
    (pin "W18")
    (pin "W19")
    (pin "Y14")
    (pin "Y15")
    (pin "Y16")
    (pin "Y17")
    (pin "Y18")
    (pin "AA10")
    (pin "AA11")
    (pin "AA12")
    (pin "AA13")
    (pin "AA7")
    (pin "AA8")
    (pin "AA9")
    (pin "AB10")
    (pin "AB11")
    (pin "AB12")
    (pin "AB7")
    (pin "AB8")
    (pin "AB9")
    (pin "AC11")
    (pin "AC12")
    (pin "AC13")
    (pin "AC7")
    (pin "AC8")
    (pin "AC9")
    (pin "AD10")
    (pin "AD11")
    (pin "AD12")
    (pin "AD13")
    (pin "AD8")
    (pin "AD9")
    (pin "AE10")
    (pin "AE11")
    (pin "AE12")
    (pin "AE13")
    (pin "AE7")
    (pin "AE8")
    (pin "AE9")
    (pin "AF10")
    (pin "AF12")
    (pin "AF13")
    (pin "AF7")
    (pin "AF8")
    (pin "AF9")
    (pin "U9")
    (pin "V10")
    (pin "V11")
    (pin "V12")
    (pin "V7")
    (pin "V8")
    (pin "V9")
    (pin "W10")
    (pin "W11")
    (pin "W7")
    (pin "W8")
    (pin "W9")
    (pin "Y10")
    (pin "Y11")
    (pin "Y12")
    (pin "Y13")
    (pin "Y7")
    (pin "Y8")
    (pin "AA1")
    (pin "AA2")
    (pin "AA3")
    (pin "AA4")
    (pin "AA5")
    (pin "AB1")
    (pin "AB2")
    (pin "AB4")
    (pin "AB5")
    (pin "AB6")
    (pin "AC1")
    (pin "AC2")
    (pin "AC3")
    (pin "AC4")
    (pin "AC5")
    (pin "AC6")
    (pin "AD1")
    (pin "AD2")
    (pin "AD3")
    (pin "AD4")
    (pin "AD5")
    (pin "AD6")
    (pin "AE1")
    (pin "AE2")
    (pin "AE3")
    (pin "AE5")
    (pin "AE6")
    (pin "AF2")
    (pin "AF3")
    (pin "AF4")
    (pin "AF5")
    (pin "AF6")
    (pin "T7")
    (pin "U1")
    (pin "U2")
    (pin "U3")
    (pin "U4")
    (pin "U5")
    (pin "U6")
    (pin "U7")
    (pin "V1")
    (pin "V2")
    (pin "V3")
    (pin "V4")
    (pin "V6")
    (pin "W1")
    (pin "W3")
    (pin "W4")
    (pin "W5")
    (pin "W6")
    (pin "Y1")
    (pin "Y2")
    (pin "Y3")
    (pin "Y4")
    (pin "Y5")
    (pin "Y6")
    (pin "A3")
    (pin "A4")
    (pin "B1")
    (pin "B2")
    (pin "B5")
    (pin "B6")
    (pin "C3")
    (pin "C4")
    (pin "D1")
    (pin "D2")
    (pin "D5")
    (pin "D6")
    (pin "E3")
    (pin "E4")
    (pin "F1")
    (pin "F2")
    (pin "F5")
    (pin "F6")
    (pin "G3")
    (pin "G4")
    (pin "H1")
    (pin "H2")
    (pin "H5")
    (pin "H6")
    (pin "J3")
    (pin "J4")
    (pin "K1")
    (pin "K2")
    (pin "K5")
    (pin "K6")
    (pin "L3")
    (pin "L4")
    (pin "M1")
    (pin "M2")
    (pin "N3")
    (pin "N4")
    (pin "P1")
    (pin "P2")
    (pin "R3")
    (pin "R4")
    (pin "A1")
    (pin "A16")
    (pin "A2")
    (pin "A26")
    (pin "A5")
    (pin "A6")
    (pin "A7")
    (pin "AA16")
    (pin "AA26")
    (pin "AA6")
    (pin "AB13")
    (pin "AB23")
    (pin "AB3")
    (pin "AC10")
    (pin "AC20")
    (pin "AD17")
    (pin "AD7")
    (pin "AE14")
    (pin "AE24")
    (pin "AE4")
    (pin "AF1")
    (pin "AF11")
    (pin "AF21")
    (pin "B13")
    (pin "B23")
    (pin "B3")
    (pin "B4")
    (pin "B7")
    (pin "C1")
    (pin "C10")
    (pin "C2")
    (pin "C20")
    (pin "C5")
    (pin "C6")
    (pin "C7")
    (pin "D17")
    (pin "D3")
    (pin "D4")
    (pin "D7")
    (pin "E1")
    (pin "E14")
    (pin "E2")
    (pin "E24")
    (pin "E5")
    (pin "E6")
    (pin "E7")
    (pin "E8")
    (pin "F11")
    (pin "F21")
    (pin "F3")
    (pin "F4")
    (pin "F7")
    (pin "G1")
    (pin "G18")
    (pin "G2")
    (pin "G5")
    (pin "G6")
    (pin "G8")
    (pin "H15")
    (pin "H25")
    (pin "H3")
    (pin "H4")
    (pin "H7")
    (pin "J1")
    (pin "J12")
    (pin "J2")
    (pin "J22")
    (pin "J5")
    (pin "J6")
    (pin "J9")
    (pin "K10")
    (pin "K11")
    (pin "K12")
    (pin "K13")
    (pin "K14")
    (pin "K19")
    (pin "K3")
    (pin "K4")
    (pin "K7")
    (pin "K8")
    (pin "K9")
    (pin "L1")
    (pin "L10")
    (pin "L11")
    (pin "L12")
    (pin "L13")
    (pin "L14")
    (pin "L15")
    (pin "L16")
    (pin "L2")
    (pin "L26")
    (pin "L5")
    (pin "L6")
    (pin "L9")
    (pin "M10")
    (pin "M11")
    (pin "M12")
    (pin "M13")
    (pin "M14")
    (pin "M15")
    (pin "M23")
    (pin "M3")
    (pin "M4")
    (pin "M5")
    (pin "M6")
    (pin "M7")
    (pin "M8")
    (pin "M9")
    (pin "N1")
    (pin "N10")
    (pin "N13")
    (pin "N14")
    (pin "N15")
    (pin "N2")
    (pin "N20")
    (pin "N5")
    (pin "N6")
    (pin "N7")
    (pin "N9")
    (pin "P10")
    (pin "P13")
    (pin "P14")
    (pin "P15")
    (pin "P17")
    (pin "P3")
    (pin "P4")
    (pin "P8")
    (pin "P9")
    (pin "R1")
    (pin "R10")
    (pin "R13")
    (pin "R14")
    (pin "R15")
    (pin "R2")
    (pin "R24")
    (pin "R5")
    (pin "R8")
    (pin "R9")
    (pin "T1")
    (pin "T10")
    (pin "T11")
    (pin "T12")
    (pin "T13")
    (pin "T14")
    (pin "T15")
    (pin "T21")
    (pin "T3")
    (pin "T4")
    (pin "T8")
    (pin "T9")
    (pin "U10")
    (pin "U11")
    (pin "U12")
    (pin "U13")
    (pin "U14")
    (pin "U15")
    (pin "U18")
    (pin "U8")
    (pin "V15")
    (pin "V25")
    (pin "V5")
    (pin "W12")
    (pin "W2")
    (pin "W22")
    (pin "Y19")
    (pin "Y9")
    (pin "C8")
    (pin "G7")
    (pin "J7")
    (pin "L7")
    (pin "L8")
    (pin "N11")
    (pin "N12")
    (pin "N8")
    (pin "P11")
    (pin "P12")
    (pin "P5")
    (pin "P6")
    (pin "P7")
    (pin "R11")
    (pin "R12")
    (pin "R6")
    (pin "R7")
    (pin "T2")
    (pin "T5")
    (pin "T6")
    (instances
      (project "data-center-rdimm-ddr4-tester"
        (path ""
          (reference "U15") (unit 1)
        )
      )
    )
  )

  (symbol (lib_id "antmicroMicrocontrollers:XC7K160T-FFG676") (at 144.78 86.995 0) (unit 2)
    (in_bom yes) (on_board yes) (dnp no) (fields_autoplaced)
    (property "Reference" "U15" (at 163.83 78.74 0)
      (effects (font (size 1.27 1.27)))
    )
    (property "Value" "XC7K160T-FFG676" (at 163.83 81.28 0)
      (effects (font (size 1.27 1.27) (thickness 0.15)))
    )
    (property "Footprint" "antmicro-footprints:BGA-676_27x27mm_Layout26x26_P1X1mm" (at 213.36 89.535 0)
      (effects (font (size 1.27 1.27) (thickness 0.15)) (justify left bottom) hide)
    )
    (property "Datasheet" "https://docs.xilinx.com/v/u/en-US/ds180_7Series_Overview" (at 213.36 92.075 0)
      (effects (font (size 1.27 1.27) (thickness 0.15)) (justify left bottom) hide)
    )
    (property "MPN" "XC7K160T-FFG676" (at 144.78 86.995 0)
      (effects (font (size 1.27 1.27)) hide)
    )
    (property "Author" "Antmicro" (at 213.36 94.615 0)
      (effects (font (size 1.27 1.27) (thickness 0.15)) (justify left bottom) hide)
    )
    (property "License" "Apache-2.0" (at 213.36 97.155 0)
      (effects (font (size 1.27 1.27) (thickness 0.15)) (justify left bottom) hide)
    )
    (property "Manufacturer" "AMD-Xilinx" (at 144.78 86.995 0)
      (effects (font (size 1.27 1.27)) hide)
    )
    (pin "AA21")
    (pin "AA22")
    (pin "AA23")
    (pin "AA24")
    (pin "AA25")
    (pin "AB21")
    (pin "AB22")
    (pin "AB24")
    (pin "AB25")
    (pin "AB26")
    (pin "AC21")
    (pin "AC22")
    (pin "AC23")
    (pin "AC24")
    (pin "AC25")
    (pin "AC26")
    (pin "AD21")
    (pin "AD22")
    (pin "AD23")
    (pin "AD24")
    (pin "AD25")
    (pin "AD26")
    (pin "AE21")
    (pin "AE22")
    (pin "AE23")
    (pin "AE25")
    (pin "AE26")
    (pin "AF22")
    (pin "AF23")
    (pin "AF24")
    (pin "AF25")
    (pin "AF26")
    (pin "U21")
    (pin "U22")
    (pin "U23")
    (pin "U24")
    (pin "U25")
    (pin "U26")
    (pin "V20")
    (pin "V21")
    (pin "V22")
    (pin "V23")
    (pin "V24")
    (pin "V26")
    (pin "W20")
    (pin "W21")
    (pin "W23")
    (pin "W24")
    (pin "W25")
    (pin "W26")
    (pin "Y20")
    (pin "Y21")
    (pin "Y22")
    (pin "Y23")
    (pin "Y24")
    (pin "Y25")
    (pin "Y26")
    (pin "K24")
    (pin "K25")
    (pin "K26")
    (pin "L24")
    (pin "L25")
    (pin "M19")
    (pin "M20")
    (pin "M21")
    (pin "M22")
    (pin "M24")
    (pin "M25")
    (pin "M26")
    (pin "N16")
    (pin "N17")
    (pin "N18")
    (pin "N19")
    (pin "N21")
    (pin "N22")
    (pin "N23")
    (pin "N24")
    (pin "N25")
    (pin "N26")
    (pin "P16")
    (pin "P18")
    (pin "P19")
    (pin "P20")
    (pin "P21")
    (pin "P22")
    (pin "P23")
    (pin "P24")
    (pin "P25")
    (pin "P26")
    (pin "R16")
    (pin "R17")
    (pin "R18")
    (pin "R19")
    (pin "R20")
    (pin "R21")
    (pin "R22")
    (pin "R23")
    (pin "R25")
    (pin "R26")
    (pin "T16")
    (pin "T17")
    (pin "T18")
    (pin "T19")
    (pin "T20")
    (pin "T22")
    (pin "T23")
    (pin "T24")
    (pin "T25")
    (pin "T26")
    (pin "U16")
    (pin "U17")
    (pin "U19")
    (pin "U20")
    (pin "A20")
    (pin "A21")
    (pin "A22")
    (pin "A23")
    (pin "A24")
    (pin "A25")
    (pin "B20")
    (pin "B21")
    (pin "B22")
    (pin "B24")
    (pin "B25")
    (pin "B26")
    (pin "C21")
    (pin "C22")
    (pin "C23")
    (pin "C24")
    (pin "C25")
    (pin "C26")
    (pin "D21")
    (pin "D22")
    (pin "D23")
    (pin "D24")
    (pin "D25")
    (pin "D26")
    (pin "E21")
    (pin "E22")
    (pin "E23")
    (pin "E25")
    (pin "E26")
    (pin "F22")
    (pin "F23")
    (pin "F24")
    (pin "F25")
    (pin "F26")
    (pin "G21")
    (pin "G22")
    (pin "G23")
    (pin "G24")
    (pin "G25")
    (pin "G26")
    (pin "H21")
    (pin "H22")
    (pin "H23")
    (pin "H24")
    (pin "H26")
    (pin "J21")
    (pin "J23")
    (pin "J24")
    (pin "J25")
    (pin "J26")
    (pin "K21")
    (pin "K22")
    (pin "K23")
    (pin "L21")
    (pin "L22")
    (pin "L23")
    (pin "A17")
    (pin "A18")
    (pin "A19")
    (pin "B16")
    (pin "B17")
    (pin "B18")
    (pin "B19")
    (pin "C16")
    (pin "C17")
    (pin "C18")
    (pin "C19")
    (pin "D15")
    (pin "D16")
    (pin "D18")
    (pin "D19")
    (pin "D20")
    (pin "E15")
    (pin "E16")
    (pin "E17")
    (pin "E18")
    (pin "E19")
    (pin "E20")
    (pin "F15")
    (pin "F16")
    (pin "F17")
    (pin "F18")
    (pin "F19")
    (pin "F20")
    (pin "G15")
    (pin "G16")
    (pin "G17")
    (pin "G19")
    (pin "G20")
    (pin "H16")
    (pin "H17")
    (pin "H18")
    (pin "H19")
    (pin "H20")
    (pin "J15")
    (pin "J16")
    (pin "J17")
    (pin "J18")
    (pin "J19")
    (pin "J20")
    (pin "K15")
    (pin "K16")
    (pin "K17")
    (pin "K18")
    (pin "K20")
    (pin "L17")
    (pin "L18")
    (pin "L19")
    (pin "L20")
    (pin "M16")
    (pin "M17")
    (pin "M18")
    (pin "A10")
    (pin "A11")
    (pin "A12")
    (pin "A13")
    (pin "A14")
    (pin "A15")
    (pin "A8")
    (pin "A9")
    (pin "B10")
    (pin "B11")
    (pin "B12")
    (pin "B14")
    (pin "B15")
    (pin "B8")
    (pin "B9")
    (pin "C11")
    (pin "C12")
    (pin "C13")
    (pin "C14")
    (pin "C15")
    (pin "C9")
    (pin "D10")
    (pin "D11")
    (pin "D12")
    (pin "D13")
    (pin "D14")
    (pin "D8")
    (pin "D9")
    (pin "E10")
    (pin "E11")
    (pin "E12")
    (pin "E13")
    (pin "E9")
    (pin "F10")
    (pin "F12")
    (pin "F13")
    (pin "F14")
    (pin "F8")
    (pin "F9")
    (pin "G10")
    (pin "G11")
    (pin "G12")
    (pin "G13")
    (pin "G14")
    (pin "G9")
    (pin "H10")
    (pin "H11")
    (pin "H12")
    (pin "H13")
    (pin "H14")
    (pin "H8")
    (pin "H9")
    (pin "J10")
    (pin "J11")
    (pin "J13")
    (pin "J14")
    (pin "J8")
    (pin "AA14")
    (pin "AA15")
    (pin "AA17")
    (pin "AA18")
    (pin "AA19")
    (pin "AA20")
    (pin "AB14")
    (pin "AB15")
    (pin "AB16")
    (pin "AB17")
    (pin "AB18")
    (pin "AB19")
    (pin "AB20")
    (pin "AC14")
    (pin "AC15")
    (pin "AC16")
    (pin "AC17")
    (pin "AC18")
    (pin "AC19")
    (pin "AD14")
    (pin "AD15")
    (pin "AD16")
    (pin "AD18")
    (pin "AD19")
    (pin "AD20")
    (pin "AE15")
    (pin "AE16")
    (pin "AE17")
    (pin "AE18")
    (pin "AE19")
    (pin "AE20")
    (pin "AF14")
    (pin "AF15")
    (pin "AF16")
    (pin "AF17")
    (pin "AF18")
    (pin "AF19")
    (pin "AF20")
    (pin "V13")
    (pin "V14")
    (pin "V16")
    (pin "V17")
    (pin "V18")
    (pin "V19")
    (pin "W13")
    (pin "W14")
    (pin "W15")
    (pin "W16")
    (pin "W17")
    (pin "W18")
    (pin "W19")
    (pin "Y14")
    (pin "Y15")
    (pin "Y16")
    (pin "Y17")
    (pin "Y18")
    (pin "AA10")
    (pin "AA11")
    (pin "AA12")
    (pin "AA13")
    (pin "AA7")
    (pin "AA8")
    (pin "AA9")
    (pin "AB10")
    (pin "AB11")
    (pin "AB12")
    (pin "AB7")
    (pin "AB8")
    (pin "AB9")
    (pin "AC11")
    (pin "AC12")
    (pin "AC13")
    (pin "AC7")
    (pin "AC8")
    (pin "AC9")
    (pin "AD10")
    (pin "AD11")
    (pin "AD12")
    (pin "AD13")
    (pin "AD8")
    (pin "AD9")
    (pin "AE10")
    (pin "AE11")
    (pin "AE12")
    (pin "AE13")
    (pin "AE7")
    (pin "AE8")
    (pin "AE9")
    (pin "AF10")
    (pin "AF12")
    (pin "AF13")
    (pin "AF7")
    (pin "AF8")
    (pin "AF9")
    (pin "U9")
    (pin "V10")
    (pin "V11")
    (pin "V12")
    (pin "V7")
    (pin "V8")
    (pin "V9")
    (pin "W10")
    (pin "W11")
    (pin "W7")
    (pin "W8")
    (pin "W9")
    (pin "Y10")
    (pin "Y11")
    (pin "Y12")
    (pin "Y13")
    (pin "Y7")
    (pin "Y8")
    (pin "AA1")
    (pin "AA2")
    (pin "AA3")
    (pin "AA4")
    (pin "AA5")
    (pin "AB1")
    (pin "AB2")
    (pin "AB4")
    (pin "AB5")
    (pin "AB6")
    (pin "AC1")
    (pin "AC2")
    (pin "AC3")
    (pin "AC4")
    (pin "AC5")
    (pin "AC6")
    (pin "AD1")
    (pin "AD2")
    (pin "AD3")
    (pin "AD4")
    (pin "AD5")
    (pin "AD6")
    (pin "AE1")
    (pin "AE2")
    (pin "AE3")
    (pin "AE5")
    (pin "AE6")
    (pin "AF2")
    (pin "AF3")
    (pin "AF4")
    (pin "AF5")
    (pin "AF6")
    (pin "T7")
    (pin "U1")
    (pin "U2")
    (pin "U3")
    (pin "U4")
    (pin "U5")
    (pin "U6")
    (pin "U7")
    (pin "V1")
    (pin "V2")
    (pin "V3")
    (pin "V4")
    (pin "V6")
    (pin "W1")
    (pin "W3")
    (pin "W4")
    (pin "W5")
    (pin "W6")
    (pin "Y1")
    (pin "Y2")
    (pin "Y3")
    (pin "Y4")
    (pin "Y5")
    (pin "Y6")
    (pin "A3")
    (pin "A4")
    (pin "B1")
    (pin "B2")
    (pin "B5")
    (pin "B6")
    (pin "C3")
    (pin "C4")
    (pin "D1")
    (pin "D2")
    (pin "D5")
    (pin "D6")
    (pin "E3")
    (pin "E4")
    (pin "F1")
    (pin "F2")
    (pin "F5")
    (pin "F6")
    (pin "G3")
    (pin "G4")
    (pin "H1")
    (pin "H2")
    (pin "H5")
    (pin "H6")
    (pin "J3")
    (pin "J4")
    (pin "K1")
    (pin "K2")
    (pin "K5")
    (pin "K6")
    (pin "L3")
    (pin "L4")
    (pin "M1")
    (pin "M2")
    (pin "N3")
    (pin "N4")
    (pin "P1")
    (pin "P2")
    (pin "R3")
    (pin "R4")
    (pin "A1")
    (pin "A16")
    (pin "A2")
    (pin "A26")
    (pin "A5")
    (pin "A6")
    (pin "A7")
    (pin "AA16")
    (pin "AA26")
    (pin "AA6")
    (pin "AB13")
    (pin "AB23")
    (pin "AB3")
    (pin "AC10")
    (pin "AC20")
    (pin "AD17")
    (pin "AD7")
    (pin "AE14")
    (pin "AE24")
    (pin "AE4")
    (pin "AF1")
    (pin "AF11")
    (pin "AF21")
    (pin "B13")
    (pin "B23")
    (pin "B3")
    (pin "B4")
    (pin "B7")
    (pin "C1")
    (pin "C10")
    (pin "C2")
    (pin "C20")
    (pin "C5")
    (pin "C6")
    (pin "C7")
    (pin "D17")
    (pin "D3")
    (pin "D4")
    (pin "D7")
    (pin "E1")
    (pin "E14")
    (pin "E2")
    (pin "E24")
    (pin "E5")
    (pin "E6")
    (pin "E7")
    (pin "E8")
    (pin "F11")
    (pin "F21")
    (pin "F3")
    (pin "F4")
    (pin "F7")
    (pin "G1")
    (pin "G18")
    (pin "G2")
    (pin "G5")
    (pin "G6")
    (pin "G8")
    (pin "H15")
    (pin "H25")
    (pin "H3")
    (pin "H4")
    (pin "H7")
    (pin "J1")
    (pin "J12")
    (pin "J2")
    (pin "J22")
    (pin "J5")
    (pin "J6")
    (pin "J9")
    (pin "K10")
    (pin "K11")
    (pin "K12")
    (pin "K13")
    (pin "K14")
    (pin "K19")
    (pin "K3")
    (pin "K4")
    (pin "K7")
    (pin "K8")
    (pin "K9")
    (pin "L1")
    (pin "L10")
    (pin "L11")
    (pin "L12")
    (pin "L13")
    (pin "L14")
    (pin "L15")
    (pin "L16")
    (pin "L2")
    (pin "L26")
    (pin "L5")
    (pin "L6")
    (pin "L9")
    (pin "M10")
    (pin "M11")
    (pin "M12")
    (pin "M13")
    (pin "M14")
    (pin "M15")
    (pin "M23")
    (pin "M3")
    (pin "M4")
    (pin "M5")
    (pin "M6")
    (pin "M7")
    (pin "M8")
    (pin "M9")
    (pin "N1")
    (pin "N10")
    (pin "N13")
    (pin "N14")
    (pin "N15")
    (pin "N2")
    (pin "N20")
    (pin "N5")
    (pin "N6")
    (pin "N7")
    (pin "N9")
    (pin "P10")
    (pin "P13")
    (pin "P14")
    (pin "P15")
    (pin "P17")
    (pin "P3")
    (pin "P4")
    (pin "P8")
    (pin "P9")
    (pin "R1")
    (pin "R10")
    (pin "R13")
    (pin "R14")
    (pin "R15")
    (pin "R2")
    (pin "R24")
    (pin "R5")
    (pin "R8")
    (pin "R9")
    (pin "T1")
    (pin "T10")
    (pin "T11")
    (pin "T12")
    (pin "T13")
    (pin "T14")
    (pin "T15")
    (pin "T21")
    (pin "T3")
    (pin "T4")
    (pin "T8")
    (pin "T9")
    (pin "U10")
    (pin "U11")
    (pin "U12")
    (pin "U13")
    (pin "U14")
    (pin "U15")
    (pin "U18")
    (pin "U8")
    (pin "V15")
    (pin "V25")
    (pin "V5")
    (pin "W12")
    (pin "W2")
    (pin "W22")
    (pin "Y19")
    (pin "Y9")
    (pin "C8")
    (pin "G7")
    (pin "J7")
    (pin "L7")
    (pin "L8")
    (pin "N11")
    (pin "N12")
    (pin "N8")
    (pin "P11")
    (pin "P12")
    (pin "P5")
    (pin "P6")
    (pin "P7")
    (pin "R11")
    (pin "R12")
    (pin "R6")
    (pin "R7")
    (pin "T2")
    (pin "T5")
    (pin "T6")
    (instances
      (project "data-center-rdimm-ddr4-tester"
        (path ""
          (reference "U15") (unit 2)
        )
      )
    )
  )

  (symbol (lib_id "antmicroMicrocontrollers:XC7K160T-FFG676") (at 327.66 86.995 0) (unit 4)
    (in_bom yes) (on_board yes) (dnp no) (fields_autoplaced)
    (property "Reference" "U15" (at 346.71 78.74 0)
      (effects (font (size 1.27 1.27)))
    )
    (property "Value" "XC7K160T-FFG676" (at 346.71 81.28 0)
      (effects (font (size 1.27 1.27) (thickness 0.15)))
    )
    (property "Footprint" "antmicro-footprints:BGA-676_27x27mm_Layout26x26_P1X1mm" (at 396.24 89.535 0)
      (effects (font (size 1.27 1.27) (thickness 0.15)) (justify left bottom) hide)
    )
    (property "Datasheet" "https://docs.xilinx.com/v/u/en-US/ds180_7Series_Overview" (at 396.24 92.075 0)
      (effects (font (size 1.27 1.27) (thickness 0.15)) (justify left bottom) hide)
    )
    (property "MPN" "XC7K160T-FFG676" (at 327.66 86.995 0)
      (effects (font (size 1.27 1.27)) hide)
    )
    (property "Author" "Antmicro" (at 396.24 94.615 0)
      (effects (font (size 1.27 1.27) (thickness 0.15)) (justify left bottom) hide)
    )
    (property "License" "Apache-2.0" (at 396.24 97.155 0)
      (effects (font (size 1.27 1.27) (thickness 0.15)) (justify left bottom) hide)
    )
    (property "Manufacturer" "AMD-Xilinx" (at 327.66 86.995 0)
      (effects (font (size 1.27 1.27)) hide)
    )
    (pin "AA21")
    (pin "AA22")
    (pin "AA23")
    (pin "AA24")
    (pin "AA25")
    (pin "AB21")
    (pin "AB22")
    (pin "AB24")
    (pin "AB25")
    (pin "AB26")
    (pin "AC21")
    (pin "AC22")
    (pin "AC23")
    (pin "AC24")
    (pin "AC25")
    (pin "AC26")
    (pin "AD21")
    (pin "AD22")
    (pin "AD23")
    (pin "AD24")
    (pin "AD25")
    (pin "AD26")
    (pin "AE21")
    (pin "AE22")
    (pin "AE23")
    (pin "AE25")
    (pin "AE26")
    (pin "AF22")
    (pin "AF23")
    (pin "AF24")
    (pin "AF25")
    (pin "AF26")
    (pin "U21")
    (pin "U22")
    (pin "U23")
    (pin "U24")
    (pin "U25")
    (pin "U26")
    (pin "V20")
    (pin "V21")
    (pin "V22")
    (pin "V23")
    (pin "V24")
    (pin "V26")
    (pin "W20")
    (pin "W21")
    (pin "W23")
    (pin "W24")
    (pin "W25")
    (pin "W26")
    (pin "Y20")
    (pin "Y21")
    (pin "Y22")
    (pin "Y23")
    (pin "Y24")
    (pin "Y25")
    (pin "Y26")
    (pin "K24")
    (pin "K25")
    (pin "K26")
    (pin "L24")
    (pin "L25")
    (pin "M19")
    (pin "M20")
    (pin "M21")
    (pin "M22")
    (pin "M24")
    (pin "M25")
    (pin "M26")
    (pin "N16")
    (pin "N17")
    (pin "N18")
    (pin "N19")
    (pin "N21")
    (pin "N22")
    (pin "N23")
    (pin "N24")
    (pin "N25")
    (pin "N26")
    (pin "P16")
    (pin "P18")
    (pin "P19")
    (pin "P20")
    (pin "P21")
    (pin "P22")
    (pin "P23")
    (pin "P24")
    (pin "P25")
    (pin "P26")
    (pin "R16")
    (pin "R17")
    (pin "R18")
    (pin "R19")
    (pin "R20")
    (pin "R21")
    (pin "R22")
    (pin "R23")
    (pin "R25")
    (pin "R26")
    (pin "T16")
    (pin "T17")
    (pin "T18")
    (pin "T19")
    (pin "T20")
    (pin "T22")
    (pin "T23")
    (pin "T24")
    (pin "T25")
    (pin "T26")
    (pin "U16")
    (pin "U17")
    (pin "U19")
    (pin "U20")
    (pin "A20")
    (pin "A21")
    (pin "A22")
    (pin "A23")
    (pin "A24")
    (pin "A25")
    (pin "B20")
    (pin "B21")
    (pin "B22")
    (pin "B24")
    (pin "B25")
    (pin "B26")
    (pin "C21")
    (pin "C22")
    (pin "C23")
    (pin "C24")
    (pin "C25")
    (pin "C26")
    (pin "D21")
    (pin "D22")
    (pin "D23")
    (pin "D24")
    (pin "D25")
    (pin "D26")
    (pin "E21")
    (pin "E22")
    (pin "E23")
    (pin "E25")
    (pin "E26")
    (pin "F22")
    (pin "F23")
    (pin "F24")
    (pin "F25")
    (pin "F26")
    (pin "G21")
    (pin "G22")
    (pin "G23")
    (pin "G24")
    (pin "G25")
    (pin "G26")
    (pin "H21")
    (pin "H22")
    (pin "H23")
    (pin "H24")
    (pin "H26")
    (pin "J21")
    (pin "J23")
    (pin "J24")
    (pin "J25")
    (pin "J26")
    (pin "K21")
    (pin "K22")
    (pin "K23")
    (pin "L21")
    (pin "L22")
    (pin "L23")
    (pin "A17")
    (pin "A18")
    (pin "A19")
    (pin "B16")
    (pin "B17")
    (pin "B18")
    (pin "B19")
    (pin "C16")
    (pin "C17")
    (pin "C18")
    (pin "C19")
    (pin "D15")
    (pin "D16")
    (pin "D18")
    (pin "D19")
    (pin "D20")
    (pin "E15")
    (pin "E16")
    (pin "E17")
    (pin "E18")
    (pin "E19")
    (pin "E20")
    (pin "F15")
    (pin "F16")
    (pin "F17")
    (pin "F18")
    (pin "F19")
    (pin "F20")
    (pin "G15")
    (pin "G16")
    (pin "G17")
    (pin "G19")
    (pin "G20")
    (pin "H16")
    (pin "H17")
    (pin "H18")
    (pin "H19")
    (pin "H20")
    (pin "J15")
    (pin "J16")
    (pin "J17")
    (pin "J18")
    (pin "J19")
    (pin "J20")
    (pin "K15")
    (pin "K16")
    (pin "K17")
    (pin "K18")
    (pin "K20")
    (pin "L17")
    (pin "L18")
    (pin "L19")
    (pin "L20")
    (pin "M16")
    (pin "M17")
    (pin "M18")
    (pin "A10")
    (pin "A11")
    (pin "A12")
    (pin "A13")
    (pin "A14")
    (pin "A15")
    (pin "A8")
    (pin "A9")
    (pin "B10")
    (pin "B11")
    (pin "B12")
    (pin "B14")
    (pin "B15")
    (pin "B8")
    (pin "B9")
    (pin "C11")
    (pin "C12")
    (pin "C13")
    (pin "C14")
    (pin "C15")
    (pin "C9")
    (pin "D10")
    (pin "D11")
    (pin "D12")
    (pin "D13")
    (pin "D14")
    (pin "D8")
    (pin "D9")
    (pin "E10")
    (pin "E11")
    (pin "E12")
    (pin "E13")
    (pin "E9")
    (pin "F10")
    (pin "F12")
    (pin "F13")
    (pin "F14")
    (pin "F8")
    (pin "F9")
    (pin "G10")
    (pin "G11")
    (pin "G12")
    (pin "G13")
    (pin "G14")
    (pin "G9")
    (pin "H10")
    (pin "H11")
    (pin "H12")
    (pin "H13")
    (pin "H14")
    (pin "H8")
    (pin "H9")
    (pin "J10")
    (pin "J11")
    (pin "J13")
    (pin "J14")
    (pin "J8")
    (pin "AA14")
    (pin "AA15")
    (pin "AA17")
    (pin "AA18")
    (pin "AA19")
    (pin "AA20")
    (pin "AB14")
    (pin "AB15")
    (pin "AB16")
    (pin "AB17")
    (pin "AB18")
    (pin "AB19")
    (pin "AB20")
    (pin "AC14")
    (pin "AC15")
    (pin "AC16")
    (pin "AC17")
    (pin "AC18")
    (pin "AC19")
    (pin "AD14")
    (pin "AD15")
    (pin "AD16")
    (pin "AD18")
    (pin "AD19")
    (pin "AD20")
    (pin "AE15")
    (pin "AE16")
    (pin "AE17")
    (pin "AE18")
    (pin "AE19")
    (pin "AE20")
    (pin "AF14")
    (pin "AF15")
    (pin "AF16")
    (pin "AF17")
    (pin "AF18")
    (pin "AF19")
    (pin "AF20")
    (pin "V13")
    (pin "V14")
    (pin "V16")
    (pin "V17")
    (pin "V18")
    (pin "V19")
    (pin "W13")
    (pin "W14")
    (pin "W15")
    (pin "W16")
    (pin "W17")
    (pin "W18")
    (pin "W19")
    (pin "Y14")
    (pin "Y15")
    (pin "Y16")
    (pin "Y17")
    (pin "Y18")
    (pin "AA10")
    (pin "AA11")
    (pin "AA12")
    (pin "AA13")
    (pin "AA7")
    (pin "AA8")
    (pin "AA9")
    (pin "AB10")
    (pin "AB11")
    (pin "AB12")
    (pin "AB7")
    (pin "AB8")
    (pin "AB9")
    (pin "AC11")
    (pin "AC12")
    (pin "AC13")
    (pin "AC7")
    (pin "AC8")
    (pin "AC9")
    (pin "AD10")
    (pin "AD11")
    (pin "AD12")
    (pin "AD13")
    (pin "AD8")
    (pin "AD9")
    (pin "AE10")
    (pin "AE11")
    (pin "AE12")
    (pin "AE13")
    (pin "AE7")
    (pin "AE8")
    (pin "AE9")
    (pin "AF10")
    (pin "AF12")
    (pin "AF13")
    (pin "AF7")
    (pin "AF8")
    (pin "AF9")
    (pin "U9")
    (pin "V10")
    (pin "V11")
    (pin "V12")
    (pin "V7")
    (pin "V8")
    (pin "V9")
    (pin "W10")
    (pin "W11")
    (pin "W7")
    (pin "W8")
    (pin "W9")
    (pin "Y10")
    (pin "Y11")
    (pin "Y12")
    (pin "Y13")
    (pin "Y7")
    (pin "Y8")
    (pin "AA1")
    (pin "AA2")
    (pin "AA3")
    (pin "AA4")
    (pin "AA5")
    (pin "AB1")
    (pin "AB2")
    (pin "AB4")
    (pin "AB5")
    (pin "AB6")
    (pin "AC1")
    (pin "AC2")
    (pin "AC3")
    (pin "AC4")
    (pin "AC5")
    (pin "AC6")
    (pin "AD1")
    (pin "AD2")
    (pin "AD3")
    (pin "AD4")
    (pin "AD5")
    (pin "AD6")
    (pin "AE1")
    (pin "AE2")
    (pin "AE3")
    (pin "AE5")
    (pin "AE6")
    (pin "AF2")
    (pin "AF3")
    (pin "AF4")
    (pin "AF5")
    (pin "AF6")
    (pin "T7")
    (pin "U1")
    (pin "U2")
    (pin "U3")
    (pin "U4")
    (pin "U5")
    (pin "U6")
    (pin "U7")
    (pin "V1")
    (pin "V2")
    (pin "V3")
    (pin "V4")
    (pin "V6")
    (pin "W1")
    (pin "W3")
    (pin "W4")
    (pin "W5")
    (pin "W6")
    (pin "Y1")
    (pin "Y2")
    (pin "Y3")
    (pin "Y4")
    (pin "Y5")
    (pin "Y6")
    (pin "A3")
    (pin "A4")
    (pin "B1")
    (pin "B2")
    (pin "B5")
    (pin "B6")
    (pin "C3")
    (pin "C4")
    (pin "D1")
    (pin "D2")
    (pin "D5")
    (pin "D6")
    (pin "E3")
    (pin "E4")
    (pin "F1")
    (pin "F2")
    (pin "F5")
    (pin "F6")
    (pin "G3")
    (pin "G4")
    (pin "H1")
    (pin "H2")
    (pin "H5")
    (pin "H6")
    (pin "J3")
    (pin "J4")
    (pin "K1")
    (pin "K2")
    (pin "K5")
    (pin "K6")
    (pin "L3")
    (pin "L4")
    (pin "M1")
    (pin "M2")
    (pin "N3")
    (pin "N4")
    (pin "P1")
    (pin "P2")
    (pin "R3")
    (pin "R4")
    (pin "A1")
    (pin "A16")
    (pin "A2")
    (pin "A26")
    (pin "A5")
    (pin "A6")
    (pin "A7")
    (pin "AA16")
    (pin "AA26")
    (pin "AA6")
    (pin "AB13")
    (pin "AB23")
    (pin "AB3")
    (pin "AC10")
    (pin "AC20")
    (pin "AD17")
    (pin "AD7")
    (pin "AE14")
    (pin "AE24")
    (pin "AE4")
    (pin "AF1")
    (pin "AF11")
    (pin "AF21")
    (pin "B13")
    (pin "B23")
    (pin "B3")
    (pin "B4")
    (pin "B7")
    (pin "C1")
    (pin "C10")
    (pin "C2")
    (pin "C20")
    (pin "C5")
    (pin "C6")
    (pin "C7")
    (pin "D17")
    (pin "D3")
    (pin "D4")
    (pin "D7")
    (pin "E1")
    (pin "E14")
    (pin "E2")
    (pin "E24")
    (pin "E5")
    (pin "E6")
    (pin "E7")
    (pin "E8")
    (pin "F11")
    (pin "F21")
    (pin "F3")
    (pin "F4")
    (pin "F7")
    (pin "G1")
    (pin "G18")
    (pin "G2")
    (pin "G5")
    (pin "G6")
    (pin "G8")
    (pin "H15")
    (pin "H25")
    (pin "H3")
    (pin "H4")
    (pin "H7")
    (pin "J1")
    (pin "J12")
    (pin "J2")
    (pin "J22")
    (pin "J5")
    (pin "J6")
    (pin "J9")
    (pin "K10")
    (pin "K11")
    (pin "K12")
    (pin "K13")
    (pin "K14")
    (pin "K19")
    (pin "K3")
    (pin "K4")
    (pin "K7")
    (pin "K8")
    (pin "K9")
    (pin "L1")
    (pin "L10")
    (pin "L11")
    (pin "L12")
    (pin "L13")
    (pin "L14")
    (pin "L15")
    (pin "L16")
    (pin "L2")
    (pin "L26")
    (pin "L5")
    (pin "L6")
    (pin "L9")
    (pin "M10")
    (pin "M11")
    (pin "M12")
    (pin "M13")
    (pin "M14")
    (pin "M15")
    (pin "M23")
    (pin "M3")
    (pin "M4")
    (pin "M5")
    (pin "M6")
    (pin "M7")
    (pin "M8")
    (pin "M9")
    (pin "N1")
    (pin "N10")
    (pin "N13")
    (pin "N14")
    (pin "N15")
    (pin "N2")
    (pin "N20")
    (pin "N5")
    (pin "N6")
    (pin "N7")
    (pin "N9")
    (pin "P10")
    (pin "P13")
    (pin "P14")
    (pin "P15")
    (pin "P17")
    (pin "P3")
    (pin "P4")
    (pin "P8")
    (pin "P9")
    (pin "R1")
    (pin "R10")
    (pin "R13")
    (pin "R14")
    (pin "R15")
    (pin "R2")
    (pin "R24")
    (pin "R5")
    (pin "R8")
    (pin "R9")
    (pin "T1")
    (pin "T10")
    (pin "T11")
    (pin "T12")
    (pin "T13")
    (pin "T14")
    (pin "T15")
    (pin "T21")
    (pin "T3")
    (pin "T4")
    (pin "T8")
    (pin "T9")
    (pin "U10")
    (pin "U11")
    (pin "U12")
    (pin "U13")
    (pin "U14")
    (pin "U15")
    (pin "U18")
    (pin "U8")
    (pin "V15")
    (pin "V25")
    (pin "V5")
    (pin "W12")
    (pin "W2")
    (pin "W22")
    (pin "Y19")
    (pin "Y9")
    (pin "C8")
    (pin "G7")
    (pin "J7")
    (pin "L7")
    (pin "L8")
    (pin "N11")
    (pin "N12")
    (pin "N8")
    (pin "P11")
    (pin "P12")
    (pin "P5")
    (pin "P6")
    (pin "P7")
    (pin "R11")
    (pin "R12")
    (pin "R6")
    (pin "R7")
    (pin "T2")
    (pin "T5")
    (pin "T6")
    (instances
      (project "data-center-rdimm-ddr4-tester"
        (path ""
          (reference "U15") (unit 4)
        )
      )
    )
  )

  (symbol (lib_id "antmicroMicrocontrollers:XC7K160T-FFG676") (at 245.11 86.995 0) (unit 3)
    (in_bom yes) (on_board yes) (dnp no) (fields_autoplaced)
    (property "Reference" "U15" (at 264.16 78.74 0)
      (effects (font (size 1.27 1.27)))
    )
    (property "Value" "XC7K160T-FFG676" (at 264.16 81.28 0)
      (effects (font (size 1.27 1.27) (thickness 0.15)))
    )
    (property "Footprint" "antmicro-footprints:BGA-676_27x27mm_Layout26x26_P1X1mm" (at 313.69 89.535 0)
      (effects (font (size 1.27 1.27) (thickness 0.15)) (justify left bottom) hide)
    )
    (property "Datasheet" "https://docs.xilinx.com/v/u/en-US/ds180_7Series_Overview" (at 313.69 92.075 0)
      (effects (font (size 1.27 1.27) (thickness 0.15)) (justify left bottom) hide)
    )
    (property "MPN" "XC7K160T-FFG676" (at 245.11 86.995 0)
      (effects (font (size 1.27 1.27)) hide)
    )
    (property "Author" "Antmicro" (at 313.69 94.615 0)
      (effects (font (size 1.27 1.27) (thickness 0.15)) (justify left bottom) hide)
    )
    (property "License" "Apache-2.0" (at 313.69 97.155 0)
      (effects (font (size 1.27 1.27) (thickness 0.15)) (justify left bottom) hide)
    )
    (property "Manufacturer" "AMD-Xilinx" (at 245.11 86.995 0)
      (effects (font (size 1.27 1.27)) hide)
    )
    (pin "AA21")
    (pin "AA22")
    (pin "AA23")
    (pin "AA24")
    (pin "AA25")
    (pin "AB21")
    (pin "AB22")
    (pin "AB24")
    (pin "AB25")
    (pin "AB26")
    (pin "AC21")
    (pin "AC22")
    (pin "AC23")
    (pin "AC24")
    (pin "AC25")
    (pin "AC26")
    (pin "AD21")
    (pin "AD22")
    (pin "AD23")
    (pin "AD24")
    (pin "AD25")
    (pin "AD26")
    (pin "AE21")
    (pin "AE22")
    (pin "AE23")
    (pin "AE25")
    (pin "AE26")
    (pin "AF22")
    (pin "AF23")
    (pin "AF24")
    (pin "AF25")
    (pin "AF26")
    (pin "U21")
    (pin "U22")
    (pin "U23")
    (pin "U24")
    (pin "U25")
    (pin "U26")
    (pin "V20")
    (pin "V21")
    (pin "V22")
    (pin "V23")
    (pin "V24")
    (pin "V26")
    (pin "W20")
    (pin "W21")
    (pin "W23")
    (pin "W24")
    (pin "W25")
    (pin "W26")
    (pin "Y20")
    (pin "Y21")
    (pin "Y22")
    (pin "Y23")
    (pin "Y24")
    (pin "Y25")
    (pin "Y26")
    (pin "K24")
    (pin "K25")
    (pin "K26")
    (pin "L24")
    (pin "L25")
    (pin "M19")
    (pin "M20")
    (pin "M21")
    (pin "M22")
    (pin "M24")
    (pin "M25")
    (pin "M26")
    (pin "N16")
    (pin "N17")
    (pin "N18")
    (pin "N19")
    (pin "N21")
    (pin "N22")
    (pin "N23")
    (pin "N24")
    (pin "N25")
    (pin "N26")
    (pin "P16")
    (pin "P18")
    (pin "P19")
    (pin "P20")
    (pin "P21")
    (pin "P22")
    (pin "P23")
    (pin "P24")
    (pin "P25")
    (pin "P26")
    (pin "R16")
    (pin "R17")
    (pin "R18")
    (pin "R19")
    (pin "R20")
    (pin "R21")
    (pin "R22")
    (pin "R23")
    (pin "R25")
    (pin "R26")
    (pin "T16")
    (pin "T17")
    (pin "T18")
    (pin "T19")
    (pin "T20")
    (pin "T22")
    (pin "T23")
    (pin "T24")
    (pin "T25")
    (pin "T26")
    (pin "U16")
    (pin "U17")
    (pin "U19")
    (pin "U20")
    (pin "A20")
    (pin "A21")
    (pin "A22")
    (pin "A23")
    (pin "A24")
    (pin "A25")
    (pin "B20")
    (pin "B21")
    (pin "B22")
    (pin "B24")
    (pin "B25")
    (pin "B26")
    (pin "C21")
    (pin "C22")
    (pin "C23")
    (pin "C24")
    (pin "C25")
    (pin "C26")
    (pin "D21")
    (pin "D22")
    (pin "D23")
    (pin "D24")
    (pin "D25")
    (pin "D26")
    (pin "E21")
    (pin "E22")
    (pin "E23")
    (pin "E25")
    (pin "E26")
    (pin "F22")
    (pin "F23")
    (pin "F24")
    (pin "F25")
    (pin "F26")
    (pin "G21")
    (pin "G22")
    (pin "G23")
    (pin "G24")
    (pin "G25")
    (pin "G26")
    (pin "H21")
    (pin "H22")
    (pin "H23")
    (pin "H24")
    (pin "H26")
    (pin "J21")
    (pin "J23")
    (pin "J24")
    (pin "J25")
    (pin "J26")
    (pin "K21")
    (pin "K22")
    (pin "K23")
    (pin "L21")
    (pin "L22")
    (pin "L23")
    (pin "A17")
    (pin "A18")
    (pin "A19")
    (pin "B16")
    (pin "B17")
    (pin "B18")
    (pin "B19")
    (pin "C16")
    (pin "C17")
    (pin "C18")
    (pin "C19")
    (pin "D15")
    (pin "D16")
    (pin "D18")
    (pin "D19")
    (pin "D20")
    (pin "E15")
    (pin "E16")
    (pin "E17")
    (pin "E18")
    (pin "E19")
    (pin "E20")
    (pin "F15")
    (pin "F16")
    (pin "F17")
    (pin "F18")
    (pin "F19")
    (pin "F20")
    (pin "G15")
    (pin "G16")
    (pin "G17")
    (pin "G19")
    (pin "G20")
    (pin "H16")
    (pin "H17")
    (pin "H18")
    (pin "H19")
    (pin "H20")
    (pin "J15")
    (pin "J16")
    (pin "J17")
    (pin "J18")
    (pin "J19")
    (pin "J20")
    (pin "K15")
    (pin "K16")
    (pin "K17")
    (pin "K18")
    (pin "K20")
    (pin "L17")
    (pin "L18")
    (pin "L19")
    (pin "L20")
    (pin "M16")
    (pin "M17")
    (pin "M18")
    (pin "A10")
    (pin "A11")
    (pin "A12")
    (pin "A13")
    (pin "A14")
    (pin "A15")
    (pin "A8")
    (pin "A9")
    (pin "B10")
    (pin "B11")
    (pin "B12")
    (pin "B14")
    (pin "B15")
    (pin "B8")
    (pin "B9")
    (pin "C11")
    (pin "C12")
    (pin "C13")
    (pin "C14")
    (pin "C15")
    (pin "C9")
    (pin "D10")
    (pin "D11")
    (pin "D12")
    (pin "D13")
    (pin "D14")
    (pin "D8")
    (pin "D9")
    (pin "E10")
    (pin "E11")
    (pin "E12")
    (pin "E13")
    (pin "E9")
    (pin "F10")
    (pin "F12")
    (pin "F13")
    (pin "F14")
    (pin "F8")
    (pin "F9")
    (pin "G10")
    (pin "G11")
    (pin "G12")
    (pin "G13")
    (pin "G14")
    (pin "G9")
    (pin "H10")
    (pin "H11")
    (pin "H12")
    (pin "H13")
    (pin "H14")
    (pin "H8")
    (pin "H9")
    (pin "J10")
    (pin "J11")
    (pin "J13")
    (pin "J14")
    (pin "J8")
    (pin "AA14")
    (pin "AA15")
    (pin "AA17")
    (pin "AA18")
    (pin "AA19")
    (pin "AA20")
    (pin "AB14")
    (pin "AB15")
    (pin "AB16")
    (pin "AB17")
    (pin "AB18")
    (pin "AB19")
    (pin "AB20")
    (pin "AC14")
    (pin "AC15")
    (pin "AC16")
    (pin "AC17")
    (pin "AC18")
    (pin "AC19")
    (pin "AD14")
    (pin "AD15")
    (pin "AD16")
    (pin "AD18")
    (pin "AD19")
    (pin "AD20")
    (pin "AE15")
    (pin "AE16")
    (pin "AE17")
    (pin "AE18")
    (pin "AE19")
    (pin "AE20")
    (pin "AF14")
    (pin "AF15")
    (pin "AF16")
    (pin "AF17")
    (pin "AF18")
    (pin "AF19")
    (pin "AF20")
    (pin "V13")
    (pin "V14")
    (pin "V16")
    (pin "V17")
    (pin "V18")
    (pin "V19")
    (pin "W13")
    (pin "W14")
    (pin "W15")
    (pin "W16")
    (pin "W17")
    (pin "W18")
    (pin "W19")
    (pin "Y14")
    (pin "Y15")
    (pin "Y16")
    (pin "Y17")
    (pin "Y18")
    (pin "AA10")
    (pin "AA11")
    (pin "AA12")
    (pin "AA13")
    (pin "AA7")
    (pin "AA8")
    (pin "AA9")
    (pin "AB10")
    (pin "AB11")
    (pin "AB12")
    (pin "AB7")
    (pin "AB8")
    (pin "AB9")
    (pin "AC11")
    (pin "AC12")
    (pin "AC13")
    (pin "AC7")
    (pin "AC8")
    (pin "AC9")
    (pin "AD10")
    (pin "AD11")
    (pin "AD12")
    (pin "AD13")
    (pin "AD8")
    (pin "AD9")
    (pin "AE10")
    (pin "AE11")
    (pin "AE12")
    (pin "AE13")
    (pin "AE7")
    (pin "AE8")
    (pin "AE9")
    (pin "AF10")
    (pin "AF12")
    (pin "AF13")
    (pin "AF7")
    (pin "AF8")
    (pin "AF9")
    (pin "U9")
    (pin "V10")
    (pin "V11")
    (pin "V12")
    (pin "V7")
    (pin "V8")
    (pin "V9")
    (pin "W10")
    (pin "W11")
    (pin "W7")
    (pin "W8")
    (pin "W9")
    (pin "Y10")
    (pin "Y11")
    (pin "Y12")
    (pin "Y13")
    (pin "Y7")
    (pin "Y8")
    (pin "AA1")
    (pin "AA2")
    (pin "AA3")
    (pin "AA4")
    (pin "AA5")
    (pin "AB1")
    (pin "AB2")
    (pin "AB4")
    (pin "AB5")
    (pin "AB6")
    (pin "AC1")
    (pin "AC2")
    (pin "AC3")
    (pin "AC4")
    (pin "AC5")
    (pin "AC6")
    (pin "AD1")
    (pin "AD2")
    (pin "AD3")
    (pin "AD4")
    (pin "AD5")
    (pin "AD6")
    (pin "AE1")
    (pin "AE2")
    (pin "AE3")
    (pin "AE5")
    (pin "AE6")
    (pin "AF2")
    (pin "AF3")
    (pin "AF4")
    (pin "AF5")
    (pin "AF6")
    (pin "T7")
    (pin "U1")
    (pin "U2")
    (pin "U3")
    (pin "U4")
    (pin "U5")
    (pin "U6")
    (pin "U7")
    (pin "V1")
    (pin "V2")
    (pin "V3")
    (pin "V4")
    (pin "V6")
    (pin "W1")
    (pin "W3")
    (pin "W4")
    (pin "W5")
    (pin "W6")
    (pin "Y1")
    (pin "Y2")
    (pin "Y3")
    (pin "Y4")
    (pin "Y5")
    (pin "Y6")
    (pin "A3")
    (pin "A4")
    (pin "B1")
    (pin "B2")
    (pin "B5")
    (pin "B6")
    (pin "C3")
    (pin "C4")
    (pin "D1")
    (pin "D2")
    (pin "D5")
    (pin "D6")
    (pin "E3")
    (pin "E4")
    (pin "F1")
    (pin "F2")
    (pin "F5")
    (pin "F6")
    (pin "G3")
    (pin "G4")
    (pin "H1")
    (pin "H2")
    (pin "H5")
    (pin "H6")
    (pin "J3")
    (pin "J4")
    (pin "K1")
    (pin "K2")
    (pin "K5")
    (pin "K6")
    (pin "L3")
    (pin "L4")
    (pin "M1")
    (pin "M2")
    (pin "N3")
    (pin "N4")
    (pin "P1")
    (pin "P2")
    (pin "R3")
    (pin "R4")
    (pin "A1")
    (pin "A16")
    (pin "A2")
    (pin "A26")
    (pin "A5")
    (pin "A6")
    (pin "A7")
    (pin "AA16")
    (pin "AA26")
    (pin "AA6")
    (pin "AB13")
    (pin "AB23")
    (pin "AB3")
    (pin "AC10")
    (pin "AC20")
    (pin "AD17")
    (pin "AD7")
    (pin "AE14")
    (pin "AE24")
    (pin "AE4")
    (pin "AF1")
    (pin "AF11")
    (pin "AF21")
    (pin "B13")
    (pin "B23")
    (pin "B3")
    (pin "B4")
    (pin "B7")
    (pin "C1")
    (pin "C10")
    (pin "C2")
    (pin "C20")
    (pin "C5")
    (pin "C6")
    (pin "C7")
    (pin "D17")
    (pin "D3")
    (pin "D4")
    (pin "D7")
    (pin "E1")
    (pin "E14")
    (pin "E2")
    (pin "E24")
    (pin "E5")
    (pin "E6")
    (pin "E7")
    (pin "E8")
    (pin "F11")
    (pin "F21")
    (pin "F3")
    (pin "F4")
    (pin "F7")
    (pin "G1")
    (pin "G18")
    (pin "G2")
    (pin "G5")
    (pin "G6")
    (pin "G8")
    (pin "H15")
    (pin "H25")
    (pin "H3")
    (pin "H4")
    (pin "H7")
    (pin "J1")
    (pin "J12")
    (pin "J2")
    (pin "J22")
    (pin "J5")
    (pin "J6")
    (pin "J9")
    (pin "K10")
    (pin "K11")
    (pin "K12")
    (pin "K13")
    (pin "K14")
    (pin "K19")
    (pin "K3")
    (pin "K4")
    (pin "K7")
    (pin "K8")
    (pin "K9")
    (pin "L1")
    (pin "L10")
    (pin "L11")
    (pin "L12")
    (pin "L13")
    (pin "L14")
    (pin "L15")
    (pin "L16")
    (pin "L2")
    (pin "L26")
    (pin "L5")
    (pin "L6")
    (pin "L9")
    (pin "M10")
    (pin "M11")
    (pin "M12")
    (pin "M13")
    (pin "M14")
    (pin "M15")
    (pin "M23")
    (pin "M3")
    (pin "M4")
    (pin "M5")
    (pin "M6")
    (pin "M7")
    (pin "M8")
    (pin "M9")
    (pin "N1")
    (pin "N10")
    (pin "N13")
    (pin "N14")
    (pin "N15")
    (pin "N2")
    (pin "N20")
    (pin "N5")
    (pin "N6")
    (pin "N7")
    (pin "N9")
    (pin "P10")
    (pin "P13")
    (pin "P14")
    (pin "P15")
    (pin "P17")
    (pin "P3")
    (pin "P4")
    (pin "P8")
    (pin "P9")
    (pin "R1")
    (pin "R10")
    (pin "R13")
    (pin "R14")
    (pin "R15")
    (pin "R2")
    (pin "R24")
    (pin "R5")
    (pin "R8")
    (pin "R9")
    (pin "T1")
    (pin "T10")
    (pin "T11")
    (pin "T12")
    (pin "T13")
    (pin "T14")
    (pin "T15")
    (pin "T21")
    (pin "T3")
    (pin "T4")
    (pin "T8")
    (pin "T9")
    (pin "U10")
    (pin "U11")
    (pin "U12")
    (pin "U13")
    (pin "U14")
    (pin "U15")
    (pin "U18")
    (pin "U8")
    (pin "V15")
    (pin "V25")
    (pin "V5")
    (pin "W12")
    (pin "W2")
    (pin "W22")
    (pin "Y19")
    (pin "Y9")
    (pin "C8")
    (pin "G7")
    (pin "J7")
    (pin "L7")
    (pin "L8")
    (pin "N11")
    (pin "N12")
    (pin "N8")
    (pin "P11")
    (pin "P12")
    (pin "P5")
    (pin "P6")
    (pin "P7")
    (pin "R11")
    (pin "R12")
    (pin "R6")
    (pin "R7")
    (pin "T2")
    (pin "T5")
    (pin "T6")
    (instances
      (project "data-center-rdimm-ddr4-tester"
        (path ""
          (reference "U15") (unit 3)
        )
      )
    )
  )
)
